FILE_TYPE = MACRO_DRAWING;
SET COLOR_WIRE YELLOW;
SET COLOR_PROP ORANGE;
SET COLOR_DOT WHITE;
SET COLOR_ARC YELLOW;
SET COLOR_BODY GREEN;
SET COLOR_NOTE PURPLE;
SET PROP_DISPLAY VALUE;
SET PAGE_NUMBER P328;
FORCEADD OFFPAGE..4
(-1600 2225);
FORCEPROP 2 LAST $XR0 304 
J 0
(-1414 2225);
DISPLAY 0.638298 (-1414 2225);
PAINT MONO (-1414 2225);
FORCEPROP 1 LAST OFFPAGE TRUE
J 0
(-1275 2100);
DISPLAY 0.872340 (-1275 2100);
PAINT GREEN (-1275 2100);
DISPLAY INVISIBLE (-1275 2100);
FORCEPROP 2 LAST CDS_LIB standard
J 0
(-1600 2225);
DISPLAY INVISIBLE (-1600 2225);
FORCEPROP 1 LAST COMMENT_BODY TRUE
J 0
(-1625 2125);
DISPLAY 0.872340 (-1625 2125);
PAINT GREEN (-1625 2125);
DISPLAY INVISIBLE (-1625 2125);
FORCEPROP 2 LAST PATH I100
J 0
(-1400 2275);
DISPLAY 1.021277 (-1400 2275);
DISPLAY INVISIBLE (-1400 2275);
FORCEADD OFFPAGE..2
(-1600 2625);
FORCEPROP 2 LAST $XR0 305 
J 0
(-1411 2625);
DISPLAY 0.638298 (-1411 2625);
PAINT MONO (-1411 2625);
FORCEPROP 2 LAST CDS_LIB standard
J 0
(-1600 2625);
DISPLAY INVISIBLE (-1600 2625);
FORCEPROP 1 LAST COMMENT_BODY TRUE
J 0
(-1645 2530);
DISPLAY 0.872340 (-1645 2530);
PAINT GREEN (-1645 2530);
DISPLAY INVISIBLE (-1645 2530);
FORCEPROP 1 LAST OFFPAGE TRUE
J 0
(-1275 2500);
DISPLAY 0.872340 (-1275 2500);
PAINT AQUA (-1275 2500);
DISPLAY INVISIBLE (-1275 2500);
FORCEPROP 2 LAST PATH I101
J 0
(-1400 2675);
DISPLAY 1.021277 (-1400 2675);
DISPLAY INVISIBLE (-1400 2675);
FORCEADD OFFPAGE..4
(-1625 3100);
FORCEPROP 2 LAST $XR0 304 
J 0
(-1439 3100);
DISPLAY 0.638298 (-1439 3100);
PAINT MONO (-1439 3100);
FORCEPROP 1 LAST COMMENT_BODY TRUE
J 0
(-1650 3000);
DISPLAY 0.872340 (-1650 3000);
PAINT GREEN (-1650 3000);
DISPLAY INVISIBLE (-1650 3000);
FORCEPROP 2 LAST CDS_LIB standard
J 0
(-1625 3100);
DISPLAY INVISIBLE (-1625 3100);
FORCEPROP 1 LAST OFFPAGE TRUE
J 0
(-1300 2975);
DISPLAY 0.872340 (-1300 2975);
PAINT GREEN (-1300 2975);
DISPLAY INVISIBLE (-1300 2975);
FORCEPROP 2 LAST PATH I102
J 0
(-1425 3150);
DISPLAY 1.021277 (-1425 3150);
DISPLAY INVISIBLE (-1425 3150);
FORCEADD OFFPAGE..4
(-1625 3000);
FORCEPROP 2 LAST $XR0 304 
J 0
(-1439 3000);
DISPLAY 0.638298 (-1439 3000);
PAINT MONO (-1439 3000);
FORCEPROP 2 LAST CDS_LIB standard
J 0
(-1625 3000);
DISPLAY INVISIBLE (-1625 3000);
FORCEPROP 1 LAST OFFPAGE TRUE
J 0
(-1300 2875);
DISPLAY 0.872340 (-1300 2875);
PAINT GREEN (-1300 2875);
DISPLAY INVISIBLE (-1300 2875);
FORCEPROP 1 LAST COMMENT_BODY TRUE
J 0
(-1650 2900);
DISPLAY 0.872340 (-1650 2900);
PAINT GREEN (-1650 2900);
DISPLAY INVISIBLE (-1650 2900);
FORCEPROP 2 LAST PATH I103
J 0
(-1425 3050);
DISPLAY 1.021277 (-1425 3050);
DISPLAY INVISIBLE (-1425 3050);
FORCEADD OFFPAGE..4
(-1625 2900);
FORCEPROP 2 LAST $XR1 305 
J 0
(-1319 2900);
DISPLAY 0.638298 (-1319 2900);
PAINT MONO (-1319 2900);
FORCEPROP 2 LAST $XR0 304 
J 0
(-1439 2900);
DISPLAY 0.638298 (-1439 2900);
PAINT MONO (-1439 2900);
FORCEPROP 1 LAST COMMENT_BODY TRUE
J 0
(-1650 2800);
DISPLAY 0.872340 (-1650 2800);
PAINT GREEN (-1650 2800);
DISPLAY INVISIBLE (-1650 2800);
FORCEPROP 1 LAST OFFPAGE TRUE
J 0
(-1300 2775);
DISPLAY 0.872340 (-1300 2775);
PAINT GREEN (-1300 2775);
DISPLAY INVISIBLE (-1300 2775);
FORCEPROP 2 LAST CDS_LIB standard
J 0
(-1625 2900);
DISPLAY INVISIBLE (-1625 2900);
FORCEPROP 2 LAST PATH I104
J 0
(-1300 2950);
DISPLAY 1.021277 (-1300 2950);
DISPLAY INVISIBLE (-1300 2950);
FORCEADD OFFPAGE..4
(-1625 3300);
FORCEPROP 2 LAST $XR0 304 
J 0
(-1439 3300);
DISPLAY 0.638298 (-1439 3300);
PAINT MONO (-1439 3300);
FORCEPROP 1 LAST OFFPAGE TRUE
J 0
(-1300 3175);
DISPLAY 0.872340 (-1300 3175);
PAINT GREEN (-1300 3175);
DISPLAY INVISIBLE (-1300 3175);
FORCEPROP 2 LAST CDS_LIB standard
J 0
(-1625 3300);
DISPLAY INVISIBLE (-1625 3300);
FORCEPROP 1 LAST COMMENT_BODY TRUE
J 0
(-1650 3200);
DISPLAY 0.872340 (-1650 3200);
PAINT GREEN (-1650 3200);
DISPLAY INVISIBLE (-1650 3200);
FORCEPROP 2 LAST PATH I105
J 0
(-1425 3350);
DISPLAY 1.021277 (-1425 3350);
DISPLAY INVISIBLE (-1425 3350);
FORCEADD OFFPAGE..4
(-1625 3200);
FORCEPROP 2 LAST $XR0 304 
J 0
(-1439 3200);
DISPLAY 0.638298 (-1439 3200);
PAINT MONO (-1439 3200);
FORCEPROP 2 LAST CDS_LIB standard
J 0
(-1625 3200);
DISPLAY INVISIBLE (-1625 3200);
FORCEPROP 1 LAST COMMENT_BODY TRUE
J 0
(-1650 3100);
DISPLAY 0.872340 (-1650 3100);
PAINT GREEN (-1650 3100);
DISPLAY INVISIBLE (-1650 3100);
FORCEPROP 1 LAST OFFPAGE TRUE
J 0
(-1300 3075);
DISPLAY 0.872340 (-1300 3075);
PAINT GREEN (-1300 3075);
DISPLAY INVISIBLE (-1300 3075);
FORCEPROP 2 LAST PATH I106
J 0
(-1425 3250);
DISPLAY 1.021277 (-1425 3250);
DISPLAY INVISIBLE (-1425 3250);
FORCEADD OFFPAGE..2
(-1625 3400);
FORCEPROP 2 LAST $XR0 305 
J 0
(-1436 3400);
DISPLAY 0.638298 (-1436 3400);
PAINT MONO (-1436 3400);
FORCEPROP 1 LAST OFFPAGE TRUE
J 0
(-1300 3275);
DISPLAY 0.872340 (-1300 3275);
PAINT AQUA (-1300 3275);
DISPLAY INVISIBLE (-1300 3275);
FORCEPROP 2 LAST CDS_LIB standard
J 0
(-1625 3400);
DISPLAY INVISIBLE (-1625 3400);
FORCEPROP 1 LAST COMMENT_BODY TRUE
J 0
(-1670 3305);
DISPLAY 0.872340 (-1670 3305);
PAINT GREEN (-1670 3305);
DISPLAY INVISIBLE (-1670 3305);
FORCEPROP 2 LAST PATH I107
J 0
(-1425 3450);
DISPLAY 1.021277 (-1425 3450);
DISPLAY INVISIBLE (-1425 3450);
FORCEADD OFFPAGE..4
(-1625 3650);
FORCEPROP 2 LAST $XR1 305 
J 0
(-1319 3650);
DISPLAY 0.638298 (-1319 3650);
PAINT MONO (-1319 3650);
FORCEPROP 2 LAST $XR0 304 
J 0
(-1439 3650);
DISPLAY 0.638298 (-1439 3650);
PAINT MONO (-1439 3650);
FORCEPROP 1 LAST COMMENT_BODY TRUE
J 0
(-1650 3550);
DISPLAY 0.872340 (-1650 3550);
PAINT GREEN (-1650 3550);
DISPLAY INVISIBLE (-1650 3550);
FORCEPROP 1 LAST OFFPAGE TRUE
J 0
(-1300 3525);
DISPLAY 0.872340 (-1300 3525);
PAINT GREEN (-1300 3525);
DISPLAY INVISIBLE (-1300 3525);
FORCEPROP 2 LAST CDS_LIB standard
J 0
(-1625 3650);
DISPLAY INVISIBLE (-1625 3650);
FORCEPROP 2 LAST PATH I108
J 0
(-1300 3700);
DISPLAY 1.021277 (-1300 3700);
DISPLAY INVISIBLE (-1300 3700);
FORCEADD OFFPAGE..4
(-1625 3850);
FORCEPROP 2 LAST $XR0 304 
J 0
(-1439 3850);
DISPLAY 0.638298 (-1439 3850);
PAINT MONO (-1439 3850);
FORCEPROP 1 LAST COMMENT_BODY TRUE
J 0
(-1650 3750);
DISPLAY 0.872340 (-1650 3750);
PAINT GREEN (-1650 3750);
DISPLAY INVISIBLE (-1650 3750);
FORCEPROP 2 LAST CDS_LIB standard
J 0
(-1625 3850);
DISPLAY INVISIBLE (-1625 3850);
FORCEPROP 1 LAST OFFPAGE TRUE
J 0
(-1300 3725);
DISPLAY 0.872340 (-1300 3725);
PAINT GREEN (-1300 3725);
DISPLAY INVISIBLE (-1300 3725);
FORCEPROP 2 LAST PATH I109
J 0
(-1425 3900);
DISPLAY 1.021277 (-1425 3900);
DISPLAY INVISIBLE (-1425 3900);
FORCEADD OFFPAGE..4
(-1625 3750);
FORCEPROP 2 LAST $XR0 304 
J 0
(-1439 3750);
DISPLAY 0.638298 (-1439 3750);
PAINT MONO (-1439 3750);
FORCEPROP 2 LAST CDS_LIB standard
J 0
(-1625 3750);
DISPLAY INVISIBLE (-1625 3750);
FORCEPROP 1 LAST OFFPAGE TRUE
J 0
(-1300 3625);
DISPLAY 0.872340 (-1300 3625);
PAINT GREEN (-1300 3625);
DISPLAY INVISIBLE (-1300 3625);
FORCEPROP 1 LAST COMMENT_BODY TRUE
J 0
(-1650 3650);
DISPLAY 0.872340 (-1650 3650);
PAINT GREEN (-1650 3650);
DISPLAY INVISIBLE (-1650 3650);
FORCEPROP 2 LAST PATH I110
J 0
(-1425 3800);
DISPLAY 1.021277 (-1425 3800);
DISPLAY INVISIBLE (-1425 3800);
FORCEADD OFFPAGE..4
(-1625 4050);
FORCEPROP 2 LAST $XR0 304 
J 0
(-1439 4050);
DISPLAY 0.638298 (-1439 4050);
PAINT MONO (-1439 4050);
FORCEPROP 1 LAST COMMENT_BODY TRUE
J 0
(-1650 3950);
DISPLAY 0.872340 (-1650 3950);
PAINT GREEN (-1650 3950);
DISPLAY INVISIBLE (-1650 3950);
FORCEPROP 1 LAST OFFPAGE TRUE
J 0
(-1300 3925);
DISPLAY 0.872340 (-1300 3925);
PAINT GREEN (-1300 3925);
DISPLAY INVISIBLE (-1300 3925);
FORCEPROP 2 LAST CDS_LIB standard
J 0
(-1625 4050);
DISPLAY INVISIBLE (-1625 4050);
FORCEPROP 2 LAST PATH I111
J 0
(-1425 4100);
DISPLAY 1.021277 (-1425 4100);
DISPLAY INVISIBLE (-1425 4100);
FORCEADD OFFPAGE..4
(-1625 3950);
FORCEPROP 2 LAST $XR0 304 
J 0
(-1439 3950);
DISPLAY 0.638298 (-1439 3950);
PAINT MONO (-1439 3950);
FORCEPROP 1 LAST COMMENT_BODY TRUE
J 0
(-1650 3850);
DISPLAY 0.872340 (-1650 3850);
PAINT GREEN (-1650 3850);
DISPLAY INVISIBLE (-1650 3850);
FORCEPROP 2 LAST CDS_LIB standard
J 0
(-1625 3950);
DISPLAY INVISIBLE (-1625 3950);
FORCEPROP 1 LAST OFFPAGE TRUE
J 0
(-1300 3825);
DISPLAY 0.872340 (-1300 3825);
PAINT GREEN (-1300 3825);
DISPLAY INVISIBLE (-1300 3825);
FORCEPROP 2 LAST PATH I112
J 0
(-1425 4000);
DISPLAY 1.021277 (-1425 4000);
DISPLAY INVISIBLE (-1425 4000);
FORCEADD OFFPAGE..2
(-1625 4150);
FORCEPROP 2 LAST $XR0 305 
J 0
(-1436 4150);
DISPLAY 0.638298 (-1436 4150);
PAINT MONO (-1436 4150);
FORCEPROP 1 LAST OFFPAGE TRUE
J 0
(-1300 4025);
DISPLAY 0.872340 (-1300 4025);
PAINT AQUA (-1300 4025);
DISPLAY INVISIBLE (-1300 4025);
FORCEPROP 1 LAST COMMENT_BODY TRUE
J 0
(-1670 4055);
DISPLAY 0.872340 (-1670 4055);
PAINT GREEN (-1670 4055);
DISPLAY INVISIBLE (-1670 4055);
FORCEPROP 2 LAST CDS_LIB standard
J 0
(-1625 4150);
DISPLAY INVISIBLE (-1625 4150);
FORCEPROP 2 LAST PATH I113
J 0
(-1425 4200);
DISPLAY 1.021277 (-1425 4200);
DISPLAY INVISIBLE (-1425 4200);
FORCEADD OFFPAGE..4
(-1600 2325);
FORCEPROP 2 LAST $XR0 304 
J 0
(-1414 2325);
DISPLAY 0.638298 (-1414 2325);
PAINT MONO (-1414 2325);
FORCEPROP 1 LAST OFFPAGE TRUE
J 0
(-1275 2200);
DISPLAY 0.872340 (-1275 2200);
PAINT GREEN (-1275 2200);
DISPLAY INVISIBLE (-1275 2200);
FORCEPROP 2 LAST CDS_LIB standard
J 0
(-1600 2325);
DISPLAY INVISIBLE (-1600 2325);
FORCEPROP 1 LAST COMMENT_BODY TRUE
J 0
(-1625 2225);
DISPLAY 0.872340 (-1625 2225);
PAINT GREEN (-1625 2225);
DISPLAY INVISIBLE (-1625 2225);
FORCEPROP 2 LAST PATH I114
J 0
(-1400 2375);
DISPLAY 1.021277 (-1400 2375);
DISPLAY INVISIBLE (-1400 2375);
FORCEADD OFFPAGE..4
(-1600 2425);
FORCEPROP 2 LAST $XR0 304 
J 0
(-1414 2425);
DISPLAY 0.638298 (-1414 2425);
PAINT MONO (-1414 2425);
FORCEPROP 1 LAST OFFPAGE TRUE
J 0
(-1275 2300);
DISPLAY 0.872340 (-1275 2300);
PAINT GREEN (-1275 2300);
DISPLAY INVISIBLE (-1275 2300);
FORCEPROP 2 LAST CDS_LIB standard
J 0
(-1600 2425);
DISPLAY INVISIBLE (-1600 2425);
FORCEPROP 1 LAST COMMENT_BODY TRUE
J 0
(-1625 2325);
DISPLAY 0.872340 (-1625 2325);
PAINT GREEN (-1625 2325);
DISPLAY INVISIBLE (-1625 2325);
FORCEPROP 2 LAST PATH I115
J 0
(-1400 2475);
DISPLAY 1.021277 (-1400 2475);
DISPLAY INVISIBLE (-1400 2475);
FORCEADD OFFPAGE..4
(-1600 2525);
FORCEPROP 2 LAST $XR0 304 
J 0
(-1414 2525);
DISPLAY 0.638298 (-1414 2525);
PAINT MONO (-1414 2525);
FORCEPROP 2 LAST CDS_LIB standard
J 0
(-1600 2525);
DISPLAY INVISIBLE (-1600 2525);
FORCEPROP 1 LAST OFFPAGE TRUE
J 0
(-1275 2400);
DISPLAY 0.872340 (-1275 2400);
PAINT GREEN (-1275 2400);
DISPLAY INVISIBLE (-1275 2400);
FORCEPROP 1 LAST COMMENT_BODY TRUE
J 0
(-1625 2425);
DISPLAY 0.872340 (-1625 2425);
PAINT GREEN (-1625 2425);
DISPLAY INVISIBLE (-1625 2425);
FORCEPROP 2 LAST PATH I116
J 0
(-1400 2575);
DISPLAY 1.021277 (-1400 2575);
DISPLAY INVISIBLE (-1400 2575);
FORCEADD Q_RES..1
(-2575 1575);
FORCEPROP 1 LAST PART_NUMBER CS01002FB07
J 0
(-2550 1375);
DISPLAY 0.723404 (-2550 1375);
PAINT WHITE (-2550 1375);
DISPLAY INVISIBLE (-2550 1375);
FORCEPROP 1 LAST MATERIAL EMPTY
J 0
(-2475 1625);
DISPLAY 0.723404 (-2475 1625);
PAINT SKYBLUE (-2475 1625);
FORCEPROP 1 LAST TOLERANCE 1%
J 0
(-2550 1625);
DISPLAY 0.723404 (-2550 1625);
PAINT SKYBLUE (-2550 1625);
FORCEPROP 1 LAST VALUE 10
J 2
(-2600 1625);
DISPLAY 0.723404 (-2600 1625);
PAINT SKYBLUE (-2600 1625);
FORCEPROP 2 LAST ROOM HSC1_BOM2
J 0
(-2250 1625);
DISPLAY 1.021277 (-2250 1625);
FORCEPROP 1 LAST LOCATION PR2527
J 0
(-2825 1575);
DISPLAY 0.723404 (-2825 1575);
PAINT AQUA (-2825 1575);
FORCEPROP 1 LASTPIN (-2675 1575) $PN 1
J 0
(-2663 1587);
DISPLAY 0.787234 (-2663 1587);
PAINT MONO (-2663 1587);
FORCEPROP 1 LASTPIN (-2475 1575) $PN 2
J 0
(-2513 1587);
DISPLAY 0.787234 (-2513 1587);
PAINT MONO (-2513 1587);
FORCEPROP 1 LAST PATH I117
J 0
(-2625 1725);
DISPLAY 0.978723 (-2625 1725);
PAINT WHITE (-2625 1725);
DISPLAY INVISIBLE (-2625 1725);
FORCEPROP 2 LAST CDS_LIB pure_quanta
J 0
(-2575 1575);
DISPLAY INVISIBLE (-2575 1575);
FORCEPROP 1 LAST PACK_TYPE 0402LF
J 0
(-2650 1525);
DISPLAY 0.723404 (-2650 1525);
PAINT SKYBLUE (-2650 1525);
DISPLAY INVISIBLE (-2650 1525);
FORCEPROP 1 LAST WATTAGE 1/16W
J 2
(-2250 1525);
DISPLAY 0.723404 (-2250 1525);
PAINT SKYBLUE (-2250 1525);
DISPLAY INVISIBLE (-2250 1525);
FORCEPROP 0 LAST $SEC 1
J 0
(-2475 1675);
DISPLAY 0.680851 (-2475 1675);
PAINT MONO (-2475 1675);
DISPLAY INVISIBLE (-2475 1675);
FORCEPROP 0 LAST CDS_SEC 1
J 0
(-2475 1675);
DISPLAY 1.021277 (-2475 1675);
DISPLAY INVISIBLE (-2475 1675);
FORCEADD Q_RES..1
(-2575 1675);
FORCEPROP 1 LAST PART_NUMBER CS01002FB07
J 0
(-2550 1475);
DISPLAY 0.723404 (-2550 1475);
PAINT WHITE (-2550 1475);
DISPLAY INVISIBLE (-2550 1475);
FORCEPROP 1 LAST MATERIAL EMPTY
J 0
(-2475 1725);
DISPLAY 0.723404 (-2475 1725);
PAINT SKYBLUE (-2475 1725);
FORCEPROP 1 LAST VALUE 10
J 2
(-2600 1725);
DISPLAY 0.723404 (-2600 1725);
PAINT SKYBLUE (-2600 1725);
FORCEPROP 1 LAST TOLERANCE 1%
J 0
(-2550 1725);
DISPLAY 0.723404 (-2550 1725);
PAINT SKYBLUE (-2550 1725);
FORCEPROP 2 LAST ROOM HSC1_BOM2
J 0
(-2250 1725);
DISPLAY 1.021277 (-2250 1725);
FORCEPROP 1 LAST LOCATION PR2526
J 0
(-2825 1675);
DISPLAY 0.723404 (-2825 1675);
PAINT AQUA (-2825 1675);
FORCEPROP 1 LASTPIN (-2675 1675) $PN 1
J 0
(-2663 1687);
DISPLAY 0.787234 (-2663 1687);
PAINT MONO (-2663 1687);
FORCEPROP 1 LASTPIN (-2475 1675) $PN 2
J 0
(-2513 1687);
DISPLAY 0.787234 (-2513 1687);
PAINT MONO (-2513 1687);
FORCEPROP 1 LAST PATH I118
J 0
(-2625 1825);
DISPLAY 0.978723 (-2625 1825);
PAINT WHITE (-2625 1825);
DISPLAY INVISIBLE (-2625 1825);
FORCEPROP 2 LAST CDS_LIB pure_quanta
J 0
(-2575 1675);
DISPLAY INVISIBLE (-2575 1675);
FORCEPROP 1 LAST PACK_TYPE 0402LF
J 0
(-2650 1625);
DISPLAY 0.723404 (-2650 1625);
PAINT SKYBLUE (-2650 1625);
DISPLAY INVISIBLE (-2650 1625);
FORCEPROP 1 LAST WATTAGE 1/16W
J 2
(-2250 1625);
DISPLAY 0.723404 (-2250 1625);
PAINT SKYBLUE (-2250 1625);
DISPLAY INVISIBLE (-2250 1625);
FORCEPROP 0 LAST $SEC 1
J 0
(-2475 1775);
DISPLAY 0.680851 (-2475 1775);
PAINT MONO (-2475 1775);
DISPLAY INVISIBLE (-2475 1775);
FORCEPROP 0 LAST CDS_SEC 1
J 0
(-2475 1775);
DISPLAY 1.021277 (-2475 1775);
DISPLAY INVISIBLE (-2475 1775);
FORCEADD Q_RES..1
(-2575 1875);
FORCEPROP 1 LAST PART_NUMBER CS01002FB07
J 0
(-2550 1675);
DISPLAY 0.723404 (-2550 1675);
PAINT WHITE (-2550 1675);
DISPLAY INVISIBLE (-2550 1675);
FORCEPROP 1 LAST MATERIAL EMPTY
J 0
(-2475 1925);
DISPLAY 0.723404 (-2475 1925);
PAINT SKYBLUE (-2475 1925);
FORCEPROP 1 LAST TOLERANCE 1%
J 0
(-2550 1925);
DISPLAY 0.723404 (-2550 1925);
PAINT SKYBLUE (-2550 1925);
FORCEPROP 1 LAST VALUE 10
J 2
(-2600 1925);
DISPLAY 0.723404 (-2600 1925);
PAINT SKYBLUE (-2600 1925);
FORCEPROP 2 LAST ROOM HSC1_BOM2
J 0
(-2250 1925);
DISPLAY 1.021277 (-2250 1925);
FORCEPROP 1 LAST LOCATION PR2524
J 0
(-2825 1875);
DISPLAY 0.723404 (-2825 1875);
PAINT AQUA (-2825 1875);
FORCEPROP 1 LASTPIN (-2675 1875) $PN 1
J 0
(-2663 1887);
DISPLAY 0.723404 (-2663 1887);
PAINT MONO (-2663 1887);
FORCEPROP 1 LASTPIN (-2475 1875) $PN 2
J 0
(-2513 1887);
DISPLAY 0.723404 (-2513 1887);
PAINT MONO (-2513 1887);
FORCEPROP 1 LAST PATH I119
J 0
(-2625 2025);
DISPLAY 0.978723 (-2625 2025);
PAINT WHITE (-2625 2025);
DISPLAY INVISIBLE (-2625 2025);
FORCEPROP 1 LAST WATTAGE 1/16W
J 2
(-2250 1825);
DISPLAY 0.723404 (-2250 1825);
PAINT SKYBLUE (-2250 1825);
DISPLAY INVISIBLE (-2250 1825);
FORCEPROP 1 LAST PACK_TYPE 0402LF
J 0
(-2650 1825);
DISPLAY 0.723404 (-2650 1825);
PAINT SKYBLUE (-2650 1825);
DISPLAY INVISIBLE (-2650 1825);
FORCEPROP 2 LAST CDS_LIB pure_quanta
J 0
(-2575 1875);
DISPLAY INVISIBLE (-2575 1875);
FORCEPROP 0 LAST $SEC 1
J 0
(-2100 1925);
DISPLAY INVISIBLE (-2100 1925);
FORCEPROP 0 LAST CDS_SEC 1
J 0
(-2100 1925);
DISPLAY INVISIBLE (-2100 1925);
FORCEADD Q_RES..1
(-2575 1775);
FORCEPROP 1 LAST PART_NUMBER CS01002FB07
J 0
(-2550 1575);
DISPLAY 0.723404 (-2550 1575);
PAINT WHITE (-2550 1575);
DISPLAY INVISIBLE (-2550 1575);
FORCEPROP 1 LAST MATERIAL EMPTY
J 0
(-2475 1825);
DISPLAY 0.723404 (-2475 1825);
PAINT SKYBLUE (-2475 1825);
FORCEPROP 1 LAST TOLERANCE 1%
J 0
(-2550 1825);
DISPLAY 0.723404 (-2550 1825);
PAINT SKYBLUE (-2550 1825);
FORCEPROP 1 LAST VALUE 10
J 2
(-2600 1825);
DISPLAY 0.723404 (-2600 1825);
PAINT SKYBLUE (-2600 1825);
FORCEPROP 2 LAST ROOM HSC1_BOM2
J 0
(-2250 1825);
DISPLAY 1.021277 (-2250 1825);
FORCEPROP 1 LAST LOCATION PR2525
J 0
(-2825 1775);
DISPLAY 0.723404 (-2825 1775);
PAINT AQUA (-2825 1775);
FORCEPROP 1 LASTPIN (-2675 1775) $PN 1
J 0
(-2663 1787);
DISPLAY 0.723404 (-2663 1787);
PAINT MONO (-2663 1787);
FORCEPROP 1 LASTPIN (-2475 1775) $PN 2
J 0
(-2513 1787);
DISPLAY 0.723404 (-2513 1787);
PAINT MONO (-2513 1787);
FORCEPROP 1 LAST PATH I120
J 0
(-2625 1925);
DISPLAY 0.978723 (-2625 1925);
PAINT WHITE (-2625 1925);
DISPLAY INVISIBLE (-2625 1925);
FORCEPROP 2 LAST CDS_LIB pure_quanta
J 0
(-2575 1775);
DISPLAY INVISIBLE (-2575 1775);
FORCEPROP 1 LAST PACK_TYPE 0402LF
J 0
(-2650 1725);
DISPLAY 0.723404 (-2650 1725);
PAINT SKYBLUE (-2650 1725);
DISPLAY INVISIBLE (-2650 1725);
FORCEPROP 1 LAST WATTAGE 1/16W
J 2
(-2250 1725);
DISPLAY 0.723404 (-2250 1725);
PAINT SKYBLUE (-2250 1725);
DISPLAY INVISIBLE (-2250 1725);
FORCEPROP 0 LAST $SEC 1
J 0
(-2100 1825);
DISPLAY INVISIBLE (-2100 1825);
FORCEPROP 0 LAST CDS_SEC 1
J 0
(-2100 1825);
DISPLAY INVISIBLE (-2100 1825);
FORCEADD OFFPAGE..4
(-1600 1675);
FORCEPROP 2 LAST $XR0 304 
J 0
(-1414 1675);
DISPLAY 0.638298 (-1414 1675);
PAINT MONO (-1414 1675);
FORCEPROP 1 LAST COMMENT_BODY TRUE
J 0
(-1625 1575);
DISPLAY 0.872340 (-1625 1575);
PAINT GREEN (-1625 1575);
DISPLAY INVISIBLE (-1625 1575);
FORCEPROP 2 LAST CDS_LIB standard
J 0
(-1600 1675);
DISPLAY INVISIBLE (-1600 1675);
FORCEPROP 1 LAST OFFPAGE TRUE
J 0
(-1275 1550);
DISPLAY 0.872340 (-1275 1550);
PAINT GREEN (-1275 1550);
DISPLAY INVISIBLE (-1275 1550);
FORCEPROP 2 LAST PATH I121
J 0
(-1400 1725);
DISPLAY 1.021277 (-1400 1725);
DISPLAY INVISIBLE (-1400 1725);
FORCEADD OFFPAGE..4
(-1600 1575);
FORCEPROP 2 LAST $XR0 304 
J 0
(-1414 1575);
DISPLAY 0.638298 (-1414 1575);
PAINT MONO (-1414 1575);
FORCEPROP 2 LAST CDS_LIB standard
J 0
(-1600 1575);
DISPLAY INVISIBLE (-1600 1575);
FORCEPROP 1 LAST COMMENT_BODY TRUE
J 0
(-1625 1475);
DISPLAY 0.872340 (-1625 1475);
PAINT GREEN (-1625 1475);
DISPLAY INVISIBLE (-1625 1475);
FORCEPROP 1 LAST OFFPAGE TRUE
J 0
(-1275 1450);
DISPLAY 0.872340 (-1275 1450);
PAINT GREEN (-1275 1450);
DISPLAY INVISIBLE (-1275 1450);
FORCEPROP 2 LAST PATH I122
J 0
(-1400 1625);
DISPLAY 1.021277 (-1400 1625);
DISPLAY INVISIBLE (-1400 1625);
FORCEADD OFFPAGE..4
(-1600 1775);
FORCEPROP 2 LAST $XR0 304 
J 0
(-1414 1775);
DISPLAY 0.638298 (-1414 1775);
PAINT MONO (-1414 1775);
FORCEPROP 2 LAST CDS_LIB standard
J 0
(-1600 1775);
DISPLAY INVISIBLE (-1600 1775);
FORCEPROP 1 LAST COMMENT_BODY TRUE
J 0
(-1625 1675);
DISPLAY 0.872340 (-1625 1675);
PAINT GREEN (-1625 1675);
DISPLAY INVISIBLE (-1625 1675);
FORCEPROP 1 LAST OFFPAGE TRUE
J 0
(-1275 1650);
DISPLAY 0.872340 (-1275 1650);
PAINT GREEN (-1275 1650);
DISPLAY INVISIBLE (-1275 1650);
FORCEPROP 2 LAST PATH I123
J 0
(-1400 1825);
DISPLAY 1.021277 (-1400 1825);
DISPLAY INVISIBLE (-1400 1825);
FORCEADD OFFPAGE..2
(-1600 1975);
FORCEPROP 2 LAST $XR0 305 
J 0
(-1411 1975);
DISPLAY 0.638298 (-1411 1975);
PAINT MONO (-1411 1975);
FORCEPROP 1 LAST OFFPAGE TRUE
J 0
(-1275 1850);
DISPLAY 0.872340 (-1275 1850);
PAINT AQUA (-1275 1850);
DISPLAY INVISIBLE (-1275 1850);
FORCEPROP 2 LAST CDS_LIB standard
J 0
(-1600 1975);
DISPLAY INVISIBLE (-1600 1975);
FORCEPROP 1 LAST COMMENT_BODY TRUE
J 0
(-1645 1880);
DISPLAY 0.872340 (-1645 1880);
PAINT GREEN (-1645 1880);
DISPLAY INVISIBLE (-1645 1880);
FORCEPROP 2 LAST PATH I124
J 0
(-1400 2025);
DISPLAY 1.021277 (-1400 2025);
DISPLAY INVISIBLE (-1400 2025);
FORCEADD OFFPAGE..4
(-1600 1875);
FORCEPROP 2 LAST $XR0 304 
J 0
(-1414 1875);
DISPLAY 0.638298 (-1414 1875);
PAINT MONO (-1414 1875);
FORCEPROP 1 LAST OFFPAGE TRUE
J 0
(-1275 1750);
DISPLAY 0.872340 (-1275 1750);
PAINT GREEN (-1275 1750);
DISPLAY INVISIBLE (-1275 1750);
FORCEPROP 2 LAST CDS_LIB standard
J 0
(-1600 1875);
DISPLAY INVISIBLE (-1600 1875);
FORCEPROP 1 LAST COMMENT_BODY TRUE
J 0
(-1625 1775);
DISPLAY 0.872340 (-1625 1775);
PAINT GREEN (-1625 1775);
DISPLAY INVISIBLE (-1625 1775);
FORCEPROP 2 LAST PATH I125
J 0
(-1400 1925);
DISPLAY 1.021277 (-1400 1925);
DISPLAY INVISIBLE (-1400 1925);
FORCEADD Q_RES_4P_12..1
R 3
(2175 4325);
FORCEPROP 1 LAST PART_NUMBER SP_CS+003DFR03_1
J 0
(2100 4650);
DISPLAY 0.574468 (2100 4650);
PAINT GREEN (2100 4650);
DISPLAY INVISIBLE (2100 4650);
FORCEPROP 2 LAST WATTAGE 3W
J 0
(2100 4550);
DISPLAY 0.638298 (2100 4550);
FORCEPROP 2 LAST TOLERANCE 1%
J 0
(2100 4500);
DISPLAY 0.638298 (2100 4500);
FORCEPROP 2 LAST VALUE 0.003
J 0
(2100 4600);
DISPLAY 0.638298 (2100 4600);
FORCEPROP 2 LAST PART_TYPE SMLF
J 0
(2100 4450);
DISPLAY 0.638298 (2100 4450);
FORCEPROP 1 LAST MATERIAL EMPTY
J 0
(2100 4700);
DISPLAY 0.595745 (2100 4700);
PAINT GREEN (2100 4700);
FORCEPROP 2 LAST ROOM HSC1_BOM2
J 0
(2100 4800);
DISPLAY 1.021277 (2100 4800);
FORCEPROP 1 LAST LOCATION PR3
J 0
(2100 4750);
DISPLAY 0.851064 (2100 4750);
PAINT GREEN (2100 4750);
FORCEPROP 0 LASTPIN (2050 4325) $PN 1
J 2
(2040 4335);
DISPLAY 0.680851 (2040 4335);
PAINT MONO (2040 4335);
FORCEPROP 0 LASTPIN (2300 4325) $PN 2
J 0
(2310 4335);
DISPLAY 0.680851 (2310 4335);
PAINT MONO (2310 4335);
FORCEPROP 0 LASTPIN (2150 4425) $PN 3
R 1
J 0
(2140 4435);
DISPLAY 0.680851 (2140 4435);
PAINT MONO (2140 4435);
FORCEPROP 0 LASTPIN (2200 4425) $PN 4
R 1
J 0
(2190 4435);
DISPLAY 0.680851 (2190 4435);
PAINT MONO (2190 4435);
FORCEPROP 1 LAST CDS_LMAN_SYM_OUTLINE -50,75,50,-75
R 1
J 2
(2175 4325);
DISPLAY 0.468085 (2175 4325);
PAINT GREEN (2175 4325);
DISPLAY INVISIBLE (2175 4325);
FORCEPROP 1 LAST NEEDS_NO_SIZE TRUE
R 1
J 2
(2176 4325);
DISPLAY 0.468085 (2176 4325);
PAINT GREEN (2176 4325);
DISPLAY INVISIBLE (2176 4325);
FORCEPROP 2 LAST CDS_LIB pure_quanta
R 1
J 2
(2175 4325);
DISPLAY INVISIBLE (2175 4325);
FORCEPROP 1 LAST PATH I126
R 1
J 2
(2175 4325);
DISPLAY 0.723404 (2175 4325);
PAINT GREEN (2175 4325);
DISPLAY INVISIBLE (2175 4325);
FORCEPROP 0 LAST $SEC 1
R 1
J 0
(2100 4800);
DISPLAY 0.680851 (2100 4800);
PAINT MONO (2100 4800);
DISPLAY INVISIBLE (2100 4800);
FORCEPROP 0 LAST CDS_SEC 1
R 1
J 0
(2100 4800);
DISPLAY 1.021277 (2100 4800);
DISPLAY INVISIBLE (2100 4800);
FORCEADD OFFPAGE..4
R 2
(-1325 275);
FORCEPROP 2 LAST $XR0 305 
J 0
(-1607 275);
DISPLAY 0.638298 (-1607 275);
PAINT MONO (-1607 275);
FORCEPROP 2 LAST CDS_LIB standard
J 0
(-1325 275);
DISPLAY INVISIBLE (-1325 275);
FORCEPROP 1 LAST COMMENT_BODY TRUE
J 2
(-1300 175);
DISPLAY 0.872340 (-1300 175);
PAINT GREEN (-1300 175);
DISPLAY INVISIBLE (-1300 175);
FORCEPROP 1 LAST OFFPAGE TRUE
J 2
(-1650 150);
DISPLAY 0.872340 (-1650 150);
PAINT GREEN (-1650 150);
DISPLAY INVISIBLE (-1650 150);
FORCEPROP 2 LAST PATH I15
J 0
(-1600 325);
DISPLAY 1.021277 (-1600 325);
DISPLAY INVISIBLE (-1600 325);
FORCEADD Q_RES..2
(-875 675);
FORCEPROP 1 LAST PART_NUMBER CS01002FB07
J 0
(-835 550);
DISPLAY 0.723404 (-835 550);
PAINT WHITE (-835 550);
DISPLAY INVISIBLE (-835 550);
FORCEPROP 1 LAST VALUE 10
J 0
(-830 750);
DISPLAY 0.723404 (-830 750);
PAINT SKYBLUE (-830 750);
FORCEPROP 1 LAST TOLERANCE 1%
J 0
(-830 700);
DISPLAY 0.723404 (-830 700);
PAINT SKYBLUE (-830 700);
FORCEPROP 1 LAST PACK_TYPE 0402LF
J 0
(-835 500);
DISPLAY 0.723404 (-835 500);
PAINT SKYBLUE (-835 500);
FORCEPROP 2 LAST ROOM HSC1_BOM2
J 0
(-825 850);
DISPLAY 1.021277 (-825 850);
FORCEPROP 1 LAST WATTAGE 1/16W
J 0
(-835 650);
DISPLAY 0.723404 (-835 650);
PAINT SKYBLUE (-835 650);
FORCEPROP 1 LAST MATERIAL EMPTY
J 0
(-835 600);
DISPLAY 0.723404 (-835 600);
PAINT SKYBLUE (-835 600);
FORCEPROP 1 LAST LOCATION PR2528
J 0
(-830 800);
DISPLAY 0.723404 (-830 800);
PAINT AQUA (-830 800);
FORCEPROP 2 LAST CDS_LIB pure_quanta
J 0
(-875 675);
PAINT MONO (-875 675);
DISPLAY INVISIBLE (-875 675);
FORCEPROP 1 LAST PATH I16
J 0
(-825 850);
DISPLAY 0.978723 (-825 850);
PAINT WHITE (-825 850);
DISPLAY INVISIBLE (-825 850);
FORCEPROP 0 LAST $SEC 1
J 0
(-825 850);
DISPLAY INVISIBLE (-825 850);
FORCEPROP 0 LAST CDS_SEC 1
J 0
(-825 850);
DISPLAY INVISIBLE (-825 850);
FORCEPROP 1 LASTPIN (-875 775) $PN 1
J 0
(-870 737);
DISPLAY 0.787234 (-870 737);
DISPLAY INVISIBLE (-870 737);
FORCEPROP 1 LASTPIN (-875 575) $PN 2
J 0
(-870 585);
DISPLAY 0.787234 (-870 585);
DISPLAY INVISIBLE (-870 585);
FORCEADD MOSFET_NCH_1D3S..1
R 6
(-525 1375);
FORCEPROP 1 LAST PART_NUMBER BAMNR580000
J 0
(-373 1466);
DISPLAY 0.723404 (-373 1466);
PAINT WHITE (-373 1466);
DISPLAY INVISIBLE (-373 1466);
FORCEPROP 2 LAST PART_TYPE SMLF
J 0
(-350 1302);
DISPLAY 1.021277 (-350 1302);
FORCEPROP 2 LAST VALUE PSMNR58-30YLH
J 0
(-350 1352);
DISPLAY 0.723404 (-350 1352);
PAINT SKYBLUE (-350 1352);
FORCEPROP 1 LAST MATERIAL EMPTY
J 0
(-373 1525);
DISPLAY 0.723404 (-373 1525);
PAINT SKYBLUE (-373 1525);
FORCEPROP 2 LAST ROOM HSC1_BOM2
J 0
(-350 1575);
DISPLAY 1.021277 (-350 1575);
FORCEPROP 1 LAST LOCATION PPQ5
J 0
(-373 1409);
DISPLAY 0.723404 (-373 1409);
PAINT AQUA (-373 1409);
FORCEPROP 0 LASTPIN (-425 1125) $PN 1
R 1
J 2
(-435 1115);
DISPLAY 0.808511 (-435 1115);
FORCEPROP 0 LASTPIN (-525 1125) $PN 2
R 1
J 2
(-535 1115);
DISPLAY 0.808511 (-535 1115);
FORCEPROP 0 LASTPIN (-625 1125) $PN 3
R 1
J 2
(-635 1115);
DISPLAY 0.808511 (-635 1115);
FORCEPROP 0 LASTPIN (-725 1325) $PN 4
J 2
(-735 1335);
DISPLAY 0.808511 (-735 1335);
FORCEPROP 0 LASTPIN (-525 1625) $PN 5
R 1
J 0
(-535 1635);
DISPLAY 0.808511 (-535 1635);
FORCEPROP 1 LAST CDS_LMAN_SYM_OUTLINE -150,200,150,-200
J 0
(-525 1353);
DISPLAY 0.468085 (-525 1353);
PAINT GREEN (-525 1353);
DISPLAY INVISIBLE (-525 1353);
FORCEPROP 1 LAST NEEDS_NO_SIZE TRUE
J 0
(-525 1354);
DISPLAY 0.468085 (-525 1354);
PAINT GREEN (-525 1354);
DISPLAY INVISIBLE (-525 1354);
FORCEPROP 2 LAST CDS_LIB pure_quanta
J 0
(-525 1328);
DISPLAY INVISIBLE (-525 1328);
FORCEPROP 1 LAST PATH I35
J 0
(-525 1375);
DISPLAY 0.723404 (-525 1375);
PAINT GREEN (-525 1375);
DISPLAY INVISIBLE (-525 1375);
FORCEPROP 0 LAST $SEC 1
J 0
(-350 1575);
DISPLAY INVISIBLE (-350 1575);
FORCEPROP 0 LAST CDS_SEC 1
J 0
(-350 1575);
DISPLAY INVISIBLE (-350 1575);
FORCEADD Q_RES..2
(0 675);
FORCEPROP 1 LAST PART_NUMBER CS01002FB07
J 0
(40 550);
DISPLAY 0.723404 (40 550);
PAINT WHITE (40 550);
DISPLAY INVISIBLE (40 550);
FORCEPROP 1 LAST VALUE 10
J 0
(45 750);
DISPLAY 0.723404 (45 750);
PAINT SKYBLUE (45 750);
FORCEPROP 1 LAST WATTAGE 1/16W
J 0
(40 650);
DISPLAY 0.723404 (40 650);
PAINT SKYBLUE (40 650);
FORCEPROP 1 LAST TOLERANCE 1%
J 0
(45 700);
DISPLAY 0.723404 (45 700);
PAINT SKYBLUE (45 700);
FORCEPROP 1 LAST MATERIAL EMPTY
J 0
(40 600);
DISPLAY 0.723404 (40 600);
PAINT SKYBLUE (40 600);
FORCEPROP 1 LAST PACK_TYPE 0402LF
J 0
(40 500);
DISPLAY 0.723404 (40 500);
PAINT SKYBLUE (40 500);
FORCEPROP 2 LAST ROOM HSC1_BOM2
J 0
(50 850);
DISPLAY 1.021277 (50 850);
FORCEPROP 1 LAST LOCATION PR2529
J 0
(45 800);
DISPLAY 0.723404 (45 800);
PAINT AQUA (45 800);
FORCEPROP 2 LAST CDS_LIB pure_quanta
J 0
(0 675);
PAINT MONO (0 675);
DISPLAY INVISIBLE (0 675);
FORCEPROP 1 LAST PATH I38
J 0
(50 850);
DISPLAY 0.978723 (50 850);
PAINT WHITE (50 850);
DISPLAY INVISIBLE (50 850);
FORCEPROP 0 LAST $SEC 1
J 0
(50 850);
DISPLAY INVISIBLE (50 850);
FORCEPROP 0 LAST CDS_SEC 1
J 0
(50 850);
DISPLAY INVISIBLE (50 850);
FORCEPROP 1 LASTPIN (0 775) $PN 1
J 0
(5 737);
DISPLAY 0.787234 (5 737);
DISPLAY INVISIBLE (5 737);
FORCEPROP 1 LASTPIN (0 575) $PN 2
J 0
(5 585);
DISPLAY 0.787234 (5 585);
DISPLAY INVISIBLE (5 585);
FORCEADD Q_RES..2
(850 675);
FORCEPROP 1 LAST PART_NUMBER CS01002FB07
J 0
(890 550);
DISPLAY 0.723404 (890 550);
PAINT WHITE (890 550);
DISPLAY INVISIBLE (890 550);
FORCEPROP 1 LAST MATERIAL EMPTY
J 0
(890 600);
DISPLAY 0.723404 (890 600);
PAINT SKYBLUE (890 600);
FORCEPROP 1 LAST VALUE 10
J 0
(895 750);
DISPLAY 0.723404 (895 750);
PAINT SKYBLUE (895 750);
FORCEPROP 1 LAST TOLERANCE 1%
J 0
(895 700);
DISPLAY 0.723404 (895 700);
PAINT SKYBLUE (895 700);
FORCEPROP 1 LAST PACK_TYPE 0402LF
J 0
(890 500);
DISPLAY 0.723404 (890 500);
PAINT SKYBLUE (890 500);
FORCEPROP 1 LAST WATTAGE 1/16W
J 0
(890 650);
DISPLAY 0.723404 (890 650);
PAINT SKYBLUE (890 650);
FORCEPROP 2 LAST ROOM HSC1_BOM2
J 0
(900 850);
DISPLAY 1.021277 (900 850);
FORCEPROP 1 LAST LOCATION PR2530
J 0
(895 800);
DISPLAY 0.723404 (895 800);
PAINT AQUA (895 800);
FORCEPROP 2 LAST CDS_LIB pure_quanta
J 0
(850 675);
PAINT MONO (850 675);
DISPLAY INVISIBLE (850 675);
FORCEPROP 1 LAST PATH I39
J 0
(900 850);
DISPLAY 0.978723 (900 850);
PAINT WHITE (900 850);
DISPLAY INVISIBLE (900 850);
FORCEPROP 0 LAST $SEC 1
J 0
(900 850);
DISPLAY INVISIBLE (900 850);
FORCEPROP 0 LAST CDS_SEC 1
J 0
(900 850);
DISPLAY INVISIBLE (900 850);
FORCEPROP 1 LASTPIN (850 775) $PN 1
J 0
(855 737);
DISPLAY 0.787234 (855 737);
DISPLAY INVISIBLE (855 737);
FORCEPROP 1 LASTPIN (850 575) $PN 2
J 0
(855 585);
DISPLAY 0.787234 (855 585);
DISPLAY INVISIBLE (855 585);
FORCEADD MOSFET_NCH_1D3S..1
R 6
(350 1400);
FORCEPROP 1 LAST PART_NUMBER BAMNR580000
J 0
(502 1491);
DISPLAY 0.723404 (502 1491);
PAINT WHITE (502 1491);
DISPLAY INVISIBLE (502 1491);
FORCEPROP 2 LAST VALUE PSMNR58-30YLH
J 0
(525 1377);
DISPLAY 0.723404 (525 1377);
PAINT SKYBLUE (525 1377);
FORCEPROP 2 LAST PART_TYPE SMLF
J 0
(525 1327);
DISPLAY 1.021277 (525 1327);
FORCEPROP 1 LAST MATERIAL EMPTY
J 0
(502 1550);
DISPLAY 0.723404 (502 1550);
PAINT SKYBLUE (502 1550);
FORCEPROP 2 LAST ROOM HSC1_BOM2
J 0
(525 1600);
DISPLAY 1.021277 (525 1600);
FORCEPROP 1 LAST LOCATION PPQ6
J 0
(502 1434);
DISPLAY 0.723404 (502 1434);
PAINT AQUA (502 1434);
FORCEPROP 0 LASTPIN (450 1150) $PN 1
R 1
J 2
(440 1140);
DISPLAY 0.808511 (440 1140);
FORCEPROP 0 LASTPIN (350 1150) $PN 2
R 1
J 2
(340 1140);
DISPLAY 0.808511 (340 1140);
FORCEPROP 0 LASTPIN (250 1150) $PN 3
R 1
J 2
(240 1140);
DISPLAY 0.808511 (240 1140);
FORCEPROP 0 LASTPIN (150 1350) $PN 4
J 2
(140 1360);
DISPLAY 0.808511 (140 1360);
FORCEPROP 0 LASTPIN (350 1650) $PN 5
R 1
J 0
(340 1660);
DISPLAY 0.808511 (340 1660);
FORCEPROP 2 LAST CDS_LIB pure_quanta
J 0
(350 1353);
DISPLAY INVISIBLE (350 1353);
FORCEPROP 1 LAST NEEDS_NO_SIZE TRUE
J 0
(350 1379);
DISPLAY 0.468085 (350 1379);
PAINT GREEN (350 1379);
DISPLAY INVISIBLE (350 1379);
FORCEPROP 1 LAST CDS_LMAN_SYM_OUTLINE -150,200,150,-200
J 0
(350 1378);
DISPLAY 0.468085 (350 1378);
PAINT GREEN (350 1378);
DISPLAY INVISIBLE (350 1378);
FORCEPROP 1 LAST PATH I40
J 0
(350 1400);
DISPLAY 0.723404 (350 1400);
PAINT GREEN (350 1400);
DISPLAY INVISIBLE (350 1400);
FORCEPROP 0 LAST $SEC 1
J 0
(525 1600);
DISPLAY INVISIBLE (525 1600);
FORCEPROP 0 LAST CDS_SEC 1
J 0
(525 1600);
DISPLAY INVISIBLE (525 1600);
FORCEADD MOSFET_NCH_1D3S..1
R 6
(1225 1425);
FORCEPROP 1 LAST PART_NUMBER BAMNR580000
J 0
(1377 1516);
DISPLAY 0.723404 (1377 1516);
PAINT WHITE (1377 1516);
DISPLAY INVISIBLE (1377 1516);
FORCEPROP 1 LAST MATERIAL EMPTY
J 0
(1377 1575);
DISPLAY 0.723404 (1377 1575);
PAINT SKYBLUE (1377 1575);
FORCEPROP 2 LAST PART_TYPE SMLF
J 0
(1400 1352);
DISPLAY 1.021277 (1400 1352);
FORCEPROP 2 LAST VALUE PSMNR58-30YLH
J 0
(1400 1402);
DISPLAY 0.723404 (1400 1402);
PAINT SKYBLUE (1400 1402);
FORCEPROP 2 LAST ROOM HSC1_BOM2
J 0
(1400 1625);
DISPLAY 1.021277 (1400 1625);
FORCEPROP 1 LAST LOCATION PPQ7
J 0
(1377 1459);
DISPLAY 0.723404 (1377 1459);
PAINT AQUA (1377 1459);
FORCEPROP 0 LASTPIN (1325 1175) $PN 1
R 1
J 2
(1315 1165);
DISPLAY 0.808511 (1315 1165);
FORCEPROP 0 LASTPIN (1225 1175) $PN 2
R 1
J 2
(1215 1165);
DISPLAY 0.808511 (1215 1165);
FORCEPROP 0 LASTPIN (1125 1175) $PN 3
R 1
J 2
(1115 1165);
DISPLAY 0.808511 (1115 1165);
FORCEPROP 0 LASTPIN (1025 1375) $PN 4
J 2
(1015 1385);
DISPLAY 0.808511 (1015 1385);
FORCEPROP 0 LASTPIN (1225 1675) $PN 5
R 1
J 0
(1215 1685);
DISPLAY 0.808511 (1215 1685);
FORCEPROP 2 LAST CDS_LIB pure_quanta
J 0
(1225 1378);
DISPLAY INVISIBLE (1225 1378);
FORCEPROP 1 LAST NEEDS_NO_SIZE TRUE
J 0
(1225 1404);
DISPLAY 0.468085 (1225 1404);
PAINT GREEN (1225 1404);
DISPLAY INVISIBLE (1225 1404);
FORCEPROP 1 LAST CDS_LMAN_SYM_OUTLINE -150,200,150,-200
J 0
(1225 1403);
DISPLAY 0.468085 (1225 1403);
PAINT GREEN (1225 1403);
DISPLAY INVISIBLE (1225 1403);
FORCEPROP 1 LAST PATH I41
J 0
(1225 1425);
DISPLAY 0.723404 (1225 1425);
PAINT GREEN (1225 1425);
DISPLAY INVISIBLE (1225 1425);
FORCEPROP 0 LAST $SEC 1
J 0
(1400 1625);
DISPLAY INVISIBLE (1400 1625);
FORCEPROP 0 LAST CDS_SEC 1
J 0
(1400 1625);
DISPLAY INVISIBLE (1400 1625);
FORCEADD OFFPAGE..2
R 2
(1075 2900);
FORCEPROP 2 LAST $XR0 304 
J 0
(820 2900);
DISPLAY 0.638298 (820 2900);
PAINT MONO (820 2900);
FORCEPROP 1 LAST OFFPAGE TRUE
J 2
(750 2775);
DISPLAY 0.872340 (750 2775);
PAINT AQUA (750 2775);
DISPLAY INVISIBLE (750 2775);
FORCEPROP 1 LAST COMMENT_BODY TRUE
J 2
(1120 2805);
DISPLAY 0.872340 (1120 2805);
PAINT GREEN (1120 2805);
DISPLAY INVISIBLE (1120 2805);
FORCEPROP 2 LAST CDS_LIB standard
J 0
(1075 2900);
DISPLAY INVISIBLE (1075 2900);
FORCEPROP 2 LAST PATH I42
J 0
(825 2950);
DISPLAY 1.021277 (825 2950);
DISPLAY INVISIBLE (825 2950);
FORCEADD OFFPAGE..2
R 2
(1075 2300);
FORCEPROP 2 LAST $XR0 304 
J 0
(820 2300);
DISPLAY 0.638298 (820 2300);
PAINT MONO (820 2300);
FORCEPROP 1 LAST COMMENT_BODY TRUE
J 2
(1120 2205);
DISPLAY 0.872340 (1120 2205);
PAINT GREEN (1120 2205);
DISPLAY INVISIBLE (1120 2205);
FORCEPROP 2 LAST CDS_LIB standard
J 0
(1075 2300);
DISPLAY INVISIBLE (1075 2300);
FORCEPROP 1 LAST OFFPAGE TRUE
J 2
(750 2175);
DISPLAY 0.872340 (750 2175);
PAINT AQUA (750 2175);
DISPLAY INVISIBLE (750 2175);
FORCEPROP 2 LAST PATH I43
J 0
(825 2350);
DISPLAY 1.021277 (825 2350);
DISPLAY INVISIBLE (825 2350);
FORCEADD OFFPAGE..5
(-725 3975);
FORCEPROP 2 LAST $XR0 301 
J 0
(-980 3975);
DISPLAY 0.638298 (-980 3975);
PAINT MONO (-980 3975);
FORCEPROP 2 LAST CDS_LIB standard
J 0
(-725 3975);
DISPLAY INVISIBLE (-725 3975);
FORCEPROP 1 LAST COMMENT_BODY TRUE
J 0
(-625 3900);
DISPLAY 1.170213 (-625 3900);
PAINT GREEN (-625 3900);
DISPLAY INVISIBLE (-625 3900);
FORCEPROP 1 LAST OFFPAGE TRUE
J 0
(-400 3850);
DISPLAY 0.872340 (-400 3850);
PAINT AQUA (-400 3850);
DISPLAY INVISIBLE (-400 3850);
FORCEPROP 2 LAST PATH I50
J 0
(-975 4025);
DISPLAY 1.021277 (-975 4025);
DISPLAY INVISIBLE (-975 4025);
FORCEADD ZENER_AC..1
R 1
(-450 3775);
FORCEPROP 1 LAST PART_NUMBER BC0MDJ14000
J 0
(-400 3675);
DISPLAY 0.723404 (-400 3675);
PAINT WHITE (-400 3675);
DISPLAY INVISIBLE (-400 3675);
FORCEPROP 1 LAST MATERIAL IC
J 0
(-400 3625);
DISPLAY 0.723404 (-400 3625);
PAINT SKYBLUE (-400 3625);
FORCEPROP 2 LAST VALUE 5.0SMDJ14A
J 0
(-400 3775);
DISPLAY 0.723404 (-400 3775);
PAINT SKYBLUE (-400 3775);
FORCEPROP 2 LAST PART_TYPE SMLF
J 0
(-400 3825);
DISPLAY 1.021277 (-400 3825);
FORCEPROP 1 LAST LOCATION PD15
J 0
(-400 3725);
DISPLAY 0.723404 (-400 3725);
PAINT AQUA (-400 3725);
FORCEPROP 0 LASTPIN (-450 3650) $PN A
R 1
J 2
(-460 3640);
DISPLAY 0.680851 (-460 3640);
PAINT MONO (-460 3640);
FORCEPROP 0 LASTPIN (-450 3900) $PN C
R 1
J 0
(-460 3910);
DISPLAY 0.680851 (-460 3910);
PAINT MONO (-460 3910);
FORCEPROP 1 LAST NEEDS_NO_SIZE TRUE
R 1
J 0
(-450 3775);
DISPLAY 0.723404 (-450 3775);
PAINT GREEN (-450 3775);
DISPLAY INVISIBLE (-450 3775);
FORCEPROP 1 LAST CDS_LMAN_SYM_OUTLINE -75,50,75,-50
R 1
J 0
(-450 3775);
DISPLAY 0.468085 (-450 3775);
PAINT GREEN (-450 3775);
DISPLAY INVISIBLE (-450 3775);
FORCEPROP 2 LAST CDS_LIB pure_quanta
J 0
(-450 3775);
DISPLAY INVISIBLE (-450 3775);
FORCEPROP 1 LAST PATH I51
R 1
J 0
(-450 3775);
DISPLAY 0.723404 (-450 3775);
PAINT GREEN (-450 3775);
DISPLAY INVISIBLE (-450 3775);
FORCEPROP 0 LAST $SEC 1
R 1
J 0
(-400 3875);
DISPLAY 0.680851 (-400 3875);
PAINT MONO (-400 3875);
DISPLAY INVISIBLE (-400 3875);
FORCEPROP 0 LAST CDS_SEC 1
R 1
J 0
(-400 3875);
DISPLAY 1.021277 (-400 3875);
DISPLAY INVISIBLE (-400 3875);
FORCEADD GND..1
(50 3525);
FORCEPROP 3 LASTPIN (50 3575) SIG_NAME GND\g
J 0
(60 3585);
DISPLAY 0.659574 (60 3585);
PAINT MONO (60 3585);
DISPLAY INVISIBLE (60 3585);
FORCEPROP 1 LAST HDL_POWER GND
J 0
(50 3675);
DISPLAY 1.170213 (50 3675);
PAINT GREEN (50 3675);
DISPLAY INVISIBLE (50 3675);
FORCEPROP 1 LAST SIZE 1B
J 0
(125 3475);
DISPLAY 0.872340 (125 3475);
PAINT AQUA (125 3475);
DISPLAY INVISIBLE (125 3475);
FORCEPROP 2 LAST CDS_LIB logical_power
J 0
(50 3525);
DISPLAY INVISIBLE (50 3525);
FORCEPROP 2 LAST ROOM VR_DDR1_POWER_STAGE
J 0
(-175 3600);
DISPLAY INVISIBLE (-175 3600);
FORCEPROP 1 LAST PATH I52
J 0
(125 3525);
DISPLAY 0.872340 (125 3525);
PAINT AQUA (125 3525);
DISPLAY INVISIBLE (125 3525);
FORCEADD ZENER_AC..1
R 1
(50 3775);
FORCEPROP 1 LAST PART_NUMBER BC0MDJ14000
J 0
(100 3675);
DISPLAY 0.723404 (100 3675);
PAINT WHITE (100 3675);
DISPLAY INVISIBLE (100 3675);
FORCEPROP 2 LAST VALUE 5.0SMDJ14A
J 0
(100 3775);
DISPLAY 0.723404 (100 3775);
PAINT SKYBLUE (100 3775);
FORCEPROP 2 LAST PART_TYPE SMLF
J 0
(100 3825);
DISPLAY 1.021277 (100 3825);
FORCEPROP 1 LAST MATERIAL IC
J 0
(100 3625);
DISPLAY 0.723404 (100 3625);
PAINT SKYBLUE (100 3625);
FORCEPROP 1 LAST LOCATION PD16
J 0
(100 3725);
DISPLAY 0.723404 (100 3725);
PAINT AQUA (100 3725);
FORCEPROP 0 LASTPIN (50 3650) $PN A
R 1
J 2
(40 3640);
DISPLAY 0.680851 (40 3640);
PAINT MONO (40 3640);
FORCEPROP 0 LASTPIN (50 3900) $PN C
R 1
J 0
(40 3910);
DISPLAY 0.680851 (40 3910);
PAINT MONO (40 3910);
FORCEPROP 1 LAST NEEDS_NO_SIZE TRUE
R 1
J 0
(50 3775);
DISPLAY 0.723404 (50 3775);
PAINT GREEN (50 3775);
DISPLAY INVISIBLE (50 3775);
FORCEPROP 2 LAST CDS_LIB pure_quanta
J 0
(50 3775);
DISPLAY INVISIBLE (50 3775);
FORCEPROP 1 LAST CDS_LMAN_SYM_OUTLINE -75,50,75,-50
R 1
J 0
(50 3775);
DISPLAY 0.468085 (50 3775);
PAINT GREEN (50 3775);
DISPLAY INVISIBLE (50 3775);
FORCEPROP 1 LAST PATH I53
R 1
J 0
(50 3775);
DISPLAY 0.723404 (50 3775);
PAINT GREEN (50 3775);
DISPLAY INVISIBLE (50 3775);
FORCEPROP 0 LAST $SEC 1
R 1
J 0
(100 3900);
DISPLAY 0.680851 (100 3900);
PAINT MONO (100 3900);
DISPLAY INVISIBLE (100 3900);
FORCEPROP 0 LAST CDS_SEC 1
R 1
J 0
(100 3900);
DISPLAY 1.021277 (100 3900);
DISPLAY INVISIBLE (100 3900);
FORCEADD Q_FUSE..1
R 3
(50 4125);
FORCEPROP 1 LAST PART_NUMBER DKK00XFU000
J 2
(525 4200);
DISPLAY 0.723404 (525 4200);
PAINT GREEN (525 4200);
DISPLAY INVISIBLE (525 4200);
FORCEPROP 2 LAST VALUE 20A/125V
J 2
(525 4150);
DISPLAY 1.021277 (525 4150);
FORCEPROP 1 LAST MATERIAL IC
J 2
(225 4250);
DISPLAY 0.723404 (225 4250);
PAINT GREEN (225 4250);
FORCEPROP 2 LAST PACK_TYPE SMLF
J 2
(325 4075);
DISPLAY 1.021277 (325 4075);
FORCEPROP 1 LAST LOCATION FS1
J 2
(175 4025);
DISPLAY 0.723404 (175 4025);
PAINT GREEN (175 4025);
FORCEPROP 0 LASTPIN (50 4225) $PN 1
R 1
J 0
(40 4235);
DISPLAY 0.680851 (40 4235);
PAINT MONO (40 4235);
FORCEPROP 0 LASTPIN (50 4025) $PN 2
R 1
J 2
(40 4015);
DISPLAY 0.680851 (40 4015);
PAINT MONO (40 4015);
FORCEPROP 2 LAST CDS_LIB pure_quanta
R 1
J 2
(50 4125);
DISPLAY INVISIBLE (50 4125);
FORCEPROP 1 LAST NEEDS_NO_SIZE TRUE
R 1
J 2
(50 4125);
DISPLAY 0.468085 (50 4125);
PAINT GREEN (50 4125);
DISPLAY INVISIBLE (50 4125);
FORCEPROP 1 LAST PATH I54
R 1
J 2
(-5 4100);
DISPLAY 0.723404 (-5 4100);
PAINT GREEN (-5 4100);
DISPLAY INVISIBLE (-5 4100);
FORCEPROP 0 LAST $SEC 1
R 1
J 0
(225 4300);
DISPLAY 0.680851 (225 4300);
PAINT MONO (225 4300);
DISPLAY INVISIBLE (225 4300);
FORCEPROP 0 LAST CDS_SEC 1
R 1
J 0
(225 4300);
DISPLAY 1.021277 (225 4300);
DISPLAY INVISIBLE (225 4300);
FORCEADD UNIVERSAL_POWER..1
(50 4400);
FORCEPROP 3 LASTPIN (50 4350) SIG_NAME P12V_PSU\g
J 0
(60 4360);
DISPLAY 0.659574 (60 4360);
PAINT MONO (60 4360);
DISPLAY INVISIBLE (60 4360);
FORCEPROP 1 LAST HDL_POWER P12V_PSU
J 1
(50 4450);
DISPLAY 0.723404 (50 4450);
PAINT GREEN (50 4450);
FORCEPROP 2 LAST ROOM AUX_SW
J 0
(50 4500);
DISPLAY 0.617021 (50 4500);
DISPLAY INVISIBLE (50 4500);
FORCEPROP 2 LAST BOM_COST MIO_VRD_SB
J 0
(50 4500);
DISPLAY 0.617021 (50 4500);
PAINT PURPLE (50 4500);
DISPLAY INVISIBLE (50 4500);
FORCEPROP 2 LAST CDS_LIB logical_power
J 0
(50 4400);
DISPLAY INVISIBLE (50 4400);
FORCEPROP 1 LAST PATH I55
J 0
(100 4425);
DISPLAY 0.872340 (100 4425);
PAINT AQUA (100 4425);
DISPLAY INVISIBLE (100 4425);
FORCEADD OFFPAGE..2
R 2
(1075 4025);
FORCEPROP 2 LAST $XR0 304 
J 0
(820 4025);
DISPLAY 0.638298 (820 4025);
PAINT MONO (820 4025);
FORCEPROP 1 LAST OFFPAGE TRUE
J 2
(750 3900);
DISPLAY 0.872340 (750 3900);
PAINT AQUA (750 3900);
DISPLAY INVISIBLE (750 3900);
FORCEPROP 1 LAST COMMENT_BODY TRUE
J 2
(1120 3930);
DISPLAY 0.872340 (1120 3930);
PAINT GREEN (1120 3930);
DISPLAY INVISIBLE (1120 3930);
FORCEPROP 2 LAST CDS_LIB standard
J 0
(1075 4025);
DISPLAY INVISIBLE (1075 4025);
FORCEPROP 2 LAST PATH I56
J 0
(825 4075);
DISPLAY 1.021277 (825 4075);
DISPLAY INVISIBLE (825 4075);
FORCEADD OFFPAGE..2
R 2
(1075 3475);
FORCEPROP 2 LAST $XR0 304 
J 0
(820 3475);
DISPLAY 0.638298 (820 3475);
PAINT MONO (820 3475);
FORCEPROP 1 LAST OFFPAGE TRUE
J 2
(750 3350);
DISPLAY 0.872340 (750 3350);
PAINT AQUA (750 3350);
DISPLAY INVISIBLE (750 3350);
FORCEPROP 2 LAST CDS_LIB standard
J 0
(1075 3475);
DISPLAY INVISIBLE (1075 3475);
FORCEPROP 1 LAST COMMENT_BODY TRUE
J 2
(1120 3380);
DISPLAY 0.872340 (1120 3380);
PAINT GREEN (1120 3380);
DISPLAY INVISIBLE (1120 3380);
FORCEPROP 2 LAST PATH I57
J 0
(825 3525);
DISPLAY 1.021277 (825 3525);
DISPLAY INVISIBLE (825 3525);
FORCEADD OFFPAGE..2
R 2
(1100 4425);
FORCEPROP 2 LAST $XR1 305 
J 0
(695 4425);
DISPLAY 0.638298 (695 4425);
PAINT MONO (695 4425);
FORCEPROP 2 LAST $XR0 304 
J 0
(815 4425);
DISPLAY 0.638298 (815 4425);
PAINT MONO (815 4425);
FORCEPROP 2 LAST PATH I58
J 0
(825 4475);
DISPLAY 1.021277 (825 4475);
DISPLAY INVISIBLE (825 4475);
FORCEPROP 1 LAST COMMENT_BODY TRUE
J 2
(1145 4330);
DISPLAY 0.872340 (1145 4330);
PAINT GREEN (1145 4330);
DISPLAY INVISIBLE (1145 4330);
FORCEPROP 2 LAST CDS_LIB standard
J 0
(1100 4425);
DISPLAY INVISIBLE (1100 4425);
FORCEPROP 1 LAST OFFPAGE TRUE
J 2
(775 4300);
DISPLAY 0.872340 (775 4300);
PAINT AQUA (775 4300);
DISPLAY INVISIBLE (775 4300);
FORCEADD Q_RES..2
(1700 675);
FORCEPROP 1 LAST PART_NUMBER CS01002FB07
J 0
(1740 550);
DISPLAY 0.723404 (1740 550);
PAINT WHITE (1740 550);
DISPLAY INVISIBLE (1740 550);
FORCEPROP 1 LAST VALUE 10
J 0
(1745 750);
DISPLAY 0.723404 (1745 750);
PAINT SKYBLUE (1745 750);
FORCEPROP 1 LAST TOLERANCE 1%
J 0
(1745 700);
DISPLAY 0.723404 (1745 700);
PAINT SKYBLUE (1745 700);
FORCEPROP 1 LAST WATTAGE 1/16W
J 0
(1740 650);
DISPLAY 0.723404 (1740 650);
PAINT SKYBLUE (1740 650);
FORCEPROP 1 LAST MATERIAL EMPTY
J 0
(1740 600);
DISPLAY 0.723404 (1740 600);
PAINT SKYBLUE (1740 600);
FORCEPROP 1 LAST PACK_TYPE 0402LF
J 0
(1740 500);
DISPLAY 0.723404 (1740 500);
PAINT SKYBLUE (1740 500);
FORCEPROP 2 LAST ROOM HSC1_BOM2
J 0
(1750 850);
DISPLAY 1.021277 (1750 850);
FORCEPROP 1 LAST LOCATION PR2531
J 0
(1745 800);
DISPLAY 0.723404 (1745 800);
PAINT AQUA (1745 800);
FORCEPROP 2 LAST CDS_LIB pure_quanta
J 0
(1700 675);
DISPLAY INVISIBLE (1700 675);
FORCEPROP 1 LAST PATH I59
J 0
(1750 850);
DISPLAY 0.978723 (1750 850);
PAINT WHITE (1750 850);
DISPLAY INVISIBLE (1750 850);
FORCEPROP 0 LAST $SEC 1
J 0
(1750 850);
DISPLAY INVISIBLE (1750 850);
FORCEPROP 0 LAST CDS_SEC 1
J 0
(1750 850);
DISPLAY INVISIBLE (1750 850);
FORCEPROP 1 LASTPIN (1700 775) $PN 1
J 0
(1705 737);
DISPLAY 0.787234 (1705 737);
PAINT MONO (1705 737);
DISPLAY INVISIBLE (1705 737);
FORCEPROP 1 LASTPIN (1700 575) $PN 2
J 0
(1705 585);
DISPLAY 0.787234 (1705 585);
PAINT MONO (1705 585);
DISPLAY INVISIBLE (1705 585);
FORCEADD Q_RES..2
(2550 675);
FORCEPROP 1 LAST PART_NUMBER CS01002FB07
J 0
(2590 550);
DISPLAY 0.723404 (2590 550);
PAINT WHITE (2590 550);
DISPLAY INVISIBLE (2590 550);
FORCEPROP 1 LAST WATTAGE 1/16W
J 0
(2590 650);
DISPLAY 0.723404 (2590 650);
PAINT SKYBLUE (2590 650);
FORCEPROP 1 LAST TOLERANCE 1%
J 0
(2595 700);
DISPLAY 0.723404 (2595 700);
PAINT SKYBLUE (2595 700);
FORCEPROP 1 LAST MATERIAL EMPTY
J 0
(2590 600);
DISPLAY 0.723404 (2590 600);
PAINT SKYBLUE (2590 600);
FORCEPROP 1 LAST VALUE 10
J 0
(2595 750);
DISPLAY 0.723404 (2595 750);
PAINT SKYBLUE (2595 750);
FORCEPROP 1 LAST PACK_TYPE 0402LF
J 0
(2590 500);
DISPLAY 0.723404 (2590 500);
PAINT SKYBLUE (2590 500);
FORCEPROP 2 LAST ROOM HSC1_BOM2
J 0
(2600 850);
DISPLAY 1.021277 (2600 850);
FORCEPROP 1 LAST LOCATION PR2535
J 0
(2595 800);
DISPLAY 0.723404 (2595 800);
PAINT AQUA (2595 800);
FORCEPROP 1 LASTPIN (2550 775) $PN 1
J 0
(2555 737);
DISPLAY 0.787234 (2555 737);
PAINT MONO (2555 737);
FORCEPROP 1 LASTPIN (2550 575) $PN 2
J 0
(2555 585);
DISPLAY 0.787234 (2555 585);
PAINT MONO (2555 585);
FORCEPROP 2 LAST CDS_LIB pure_quanta
J 0
(2550 675);
DISPLAY INVISIBLE (2550 675);
FORCEPROP 1 LAST PATH I60
J 0
(2600 850);
DISPLAY 0.978723 (2600 850);
PAINT WHITE (2600 850);
DISPLAY INVISIBLE (2600 850);
FORCEPROP 0 LAST $SEC 1
J 0
(2600 850);
DISPLAY 0.680851 (2600 850);
PAINT MONO (2600 850);
DISPLAY INVISIBLE (2600 850);
FORCEPROP 0 LAST CDS_SEC 1
J 0
(2600 850);
DISPLAY 1.021277 (2600 850);
DISPLAY INVISIBLE (2600 850);
FORCEADD Q_RES..2
(3425 675);
FORCEPROP 1 LAST PART_NUMBER CS01002FB07
J 0
(3465 550);
DISPLAY 0.723404 (3465 550);
PAINT WHITE (3465 550);
DISPLAY INVISIBLE (3465 550);
FORCEPROP 1 LAST MATERIAL EMPTY
J 0
(3465 600);
DISPLAY 0.723404 (3465 600);
PAINT SKYBLUE (3465 600);
FORCEPROP 1 LAST VALUE 10
J 0
(3470 750);
DISPLAY 0.723404 (3470 750);
PAINT SKYBLUE (3470 750);
FORCEPROP 1 LAST WATTAGE 1/16W
J 0
(3465 650);
DISPLAY 0.723404 (3465 650);
PAINT SKYBLUE (3465 650);
FORCEPROP 1 LAST TOLERANCE 1%
J 0
(3470 700);
DISPLAY 0.723404 (3470 700);
PAINT SKYBLUE (3470 700);
FORCEPROP 1 LAST PACK_TYPE 0402LF
J 0
(3465 500);
DISPLAY 0.723404 (3465 500);
PAINT SKYBLUE (3465 500);
FORCEPROP 2 LAST ROOM HSC1_BOM2
J 0
(3475 850);
DISPLAY 1.021277 (3475 850);
FORCEPROP 1 LAST LOCATION PR2536
J 0
(3470 800);
DISPLAY 0.723404 (3470 800);
PAINT AQUA (3470 800);
FORCEPROP 1 LASTPIN (3425 775) $PN 1
J 0
(3430 737);
DISPLAY 0.787234 (3430 737);
PAINT MONO (3430 737);
FORCEPROP 1 LASTPIN (3425 575) $PN 2
J 0
(3430 585);
DISPLAY 0.787234 (3430 585);
PAINT MONO (3430 585);
FORCEPROP 2 LAST CDS_LIB pure_quanta
J 0
(3425 675);
DISPLAY INVISIBLE (3425 675);
FORCEPROP 1 LAST PATH I61
J 0
(3475 850);
DISPLAY 0.978723 (3475 850);
PAINT WHITE (3475 850);
DISPLAY INVISIBLE (3475 850);
FORCEPROP 0 LAST $SEC 1
J 0
(3475 850);
DISPLAY 0.680851 (3475 850);
PAINT MONO (3475 850);
DISPLAY INVISIBLE (3475 850);
FORCEPROP 0 LAST CDS_SEC 1
J 0
(3475 850);
DISPLAY 1.021277 (3475 850);
DISPLAY INVISIBLE (3475 850);
FORCEADD MOSFET_NCH_1D3S..1
R 6
(2100 1425);
FORCEPROP 1 LAST PART_NUMBER BAMNR580000
J 0
(2252 1516);
DISPLAY 0.723404 (2252 1516);
PAINT WHITE (2252 1516);
DISPLAY INVISIBLE (2252 1516);
FORCEPROP 2 LAST VALUE PSMNR58-30YLH
J 0
(2275 1402);
DISPLAY 0.723404 (2275 1402);
PAINT SKYBLUE (2275 1402);
FORCEPROP 1 LAST MATERIAL EMPTY
J 0
(2252 1575);
DISPLAY 0.723404 (2252 1575);
PAINT SKYBLUE (2252 1575);
FORCEPROP 2 LAST PART_TYPE SMLF
J 0
(2275 1352);
DISPLAY 1.021277 (2275 1352);
FORCEPROP 2 LAST ROOM HSC1_BOM2
J 0
(2275 1625);
DISPLAY 1.021277 (2275 1625);
FORCEPROP 1 LAST LOCATION PPQ8
J 0
(2252 1459);
DISPLAY 0.723404 (2252 1459);
PAINT AQUA (2252 1459);
FORCEPROP 0 LASTPIN (2200 1175) $PN 1
R 1
J 2
(2190 1165);
DISPLAY 0.808511 (2190 1165);
FORCEPROP 0 LASTPIN (2100 1175) $PN 2
R 1
J 2
(2090 1165);
DISPLAY 0.808511 (2090 1165);
FORCEPROP 0 LASTPIN (2000 1175) $PN 3
R 1
J 2
(1990 1165);
DISPLAY 0.808511 (1990 1165);
FORCEPROP 0 LASTPIN (1900 1375) $PN 4
J 2
(1890 1385);
DISPLAY 0.808511 (1890 1385);
FORCEPROP 0 LASTPIN (2100 1675) $PN 5
R 1
J 0
(2090 1685);
DISPLAY 0.808511 (2090 1685);
FORCEPROP 1 LAST CDS_LMAN_SYM_OUTLINE -150,200,150,-200
J 0
(2100 1403);
DISPLAY 0.468085 (2100 1403);
PAINT GREEN (2100 1403);
DISPLAY INVISIBLE (2100 1403);
FORCEPROP 1 LAST NEEDS_NO_SIZE TRUE
J 0
(2100 1404);
DISPLAY 0.468085 (2100 1404);
PAINT GREEN (2100 1404);
DISPLAY INVISIBLE (2100 1404);
FORCEPROP 2 LAST CDS_LIB pure_quanta
J 0
(2100 1378);
DISPLAY INVISIBLE (2100 1378);
FORCEPROP 1 LAST PATH I62
J 0
(2100 1425);
DISPLAY 0.723404 (2100 1425);
PAINT GREEN (2100 1425);
DISPLAY INVISIBLE (2100 1425);
FORCEPROP 0 LAST $SEC 1
J 0
(2275 1625);
DISPLAY INVISIBLE (2275 1625);
FORCEPROP 0 LAST CDS_SEC 1
J 0
(2275 1625);
DISPLAY INVISIBLE (2275 1625);
FORCEADD Q_SP_RES4P..1
(2150 2325);
FORCEPROP 1 LAST PART_NUMBER SP_CS0000FFT04
J 0
(1900 2142);
DISPLAY 0.723404 (1900 2142);
PAINT WHITE (1900 2142);
DISPLAY INVISIBLE (1900 2142);
FORCEPROP 2 LAST VALUE 0.0003
J 0
(2400 2050);
DISPLAY 0.723404 (2400 2050);
PAINT SKYBLUE (2400 2050);
FORCEPROP 2 LAST PART_TYPE SMLF
J 0
(2400 2200);
DISPLAY 1.021277 (2400 2200);
FORCEPROP 1 LAST MATERIAL EMPTY
J 0
(1900 2082);
DISPLAY 0.723404 (1900 2082);
PAINT SKYBLUE (1900 2082);
FORCEPROP 2 LAST TOLERANCE 1%
J 0
(2400 2100);
DISPLAY 0.723404 (2400 2100);
PAINT SKYBLUE (2400 2100);
FORCEPROP 2 LAST WATTAGE 4W
J 0
(2400 2150);
DISPLAY 0.723404 (2400 2150);
PAINT SKYBLUE (2400 2150);
FORCEPROP 2 LAST ROOM HSC1_BOM2
J 0
(2400 2250);
DISPLAY 1.021277 (2400 2250);
FORCEPROP 1 LAST LOCATION PR2534
J 0
(1900 2200);
DISPLAY 0.723404 (1900 2200);
PAINT AQUA (1900 2200);
FORCEPROP 0 LASTPIN (1950 2350) $PN 1A
J 2
(1940 2360);
DISPLAY 0.680851 (1940 2360);
PAINT MONO (1940 2360);
FORCEPROP 0 LASTPIN (1950 2300) $PN 1B
J 2
(1940 2310);
DISPLAY 0.680851 (1940 2310);
PAINT MONO (1940 2310);
FORCEPROP 0 LASTPIN (2350 2350) $PN 2A
J 0
(2360 2360);
DISPLAY 0.680851 (2360 2360);
PAINT MONO (2360 2360);
FORCEPROP 0 LASTPIN (2350 2300) $PN 2B
J 0
(2360 2310);
DISPLAY 0.680851 (2360 2310);
PAINT MONO (2360 2310);
FORCEPROP 1 LAST NEEDS_NO_SIZE TRUE
J 0
(2300 2331);
DISPLAY 0.468085 (2300 2331);
PAINT GREEN (2300 2331);
DISPLAY INVISIBLE (2300 2331);
FORCEPROP 2 LAST CDS_LIB pure_quanta
J 0
(2150 2325);
DISPLAY INVISIBLE (2150 2325);
FORCEPROP 1 LAST CDS_LMAN_SYM_OUTLINE -150,75,150,-75
J 0
(2150 2325);
DISPLAY 0.468085 (2150 2325);
PAINT GREEN (2150 2325);
DISPLAY INVISIBLE (2150 2325);
FORCEPROP 1 LAST PATH I63
J 0
(2150 2325);
DISPLAY 0.723404 (2150 2325);
PAINT GREEN (2150 2325);
DISPLAY INVISIBLE (2150 2325);
FORCEPROP 0 LAST $SEC 1
J 0
(2000 2825);
DISPLAY 0.680851 (2000 2825);
PAINT MONO (2000 2825);
DISPLAY INVISIBLE (2000 2825);
FORCEPROP 0 LAST CDS_SEC 1
J 0
(2000 2825);
DISPLAY 1.021277 (2000 2825);
DISPLAY INVISIBLE (2000 2825);
FORCEADD Q_SP_RES4P..1
(2150 2925);
FORCEPROP 1 LAST PART_NUMBER SP_CS0000FFT04
J 0
(2025 2710);
DISPLAY 0.723404 (2025 2710);
PAINT WHITE (2025 2710);
DISPLAY INVISIBLE (2025 2710);
FORCEPROP 1 LAST MATERIAL EMPTY
J 0
(2025 2650);
DISPLAY 0.723404 (2025 2650);
PAINT SKYBLUE (2025 2650);
FORCEPROP 2 LAST PART_TYPE SMLF
J 0
(2025 2575);
DISPLAY 1.021277 (2025 2575);
FORCEPROP 2 LAST VALUE 0.0003
J 0
(2025 2425);
DISPLAY 0.723404 (2025 2425);
PAINT SKYBLUE (2025 2425);
FORCEPROP 2 LAST WATTAGE 4W
J 0
(2025 2525);
DISPLAY 0.723404 (2025 2525);
PAINT SKYBLUE (2025 2525);
FORCEPROP 2 LAST TOLERANCE 1%
J 0
(2025 2475);
DISPLAY 0.723404 (2025 2475);
PAINT SKYBLUE (2025 2475);
FORCEPROP 2 LAST ROOM HSC1_BOM2
J 0
(2050 2800);
DISPLAY 1.021277 (2050 2800);
FORCEPROP 1 LAST LOCATION PR2533
J 0
(2025 2768);
DISPLAY 0.723404 (2025 2768);
PAINT AQUA (2025 2768);
FORCEPROP 0 LASTPIN (1950 2950) $PN 1A
J 2
(1940 2960);
DISPLAY 0.808511 (1940 2960);
FORCEPROP 0 LASTPIN (1950 2900) $PN 1B
J 2
(1940 2910);
DISPLAY 0.808511 (1940 2910);
FORCEPROP 0 LASTPIN (2350 2950) $PN 2A
J 0
(2360 2960);
DISPLAY 0.808511 (2360 2960);
FORCEPROP 0 LASTPIN (2350 2900) $PN 2B
J 0
(2360 2910);
DISPLAY 0.808511 (2360 2910);
FORCEPROP 2 LAST CDS_LIB pure_quanta
J 0
(2150 2925);
DISPLAY INVISIBLE (2150 2925);
FORCEPROP 1 LAST CDS_LMAN_SYM_OUTLINE -150,75,150,-75
J 0
(2150 2925);
DISPLAY 0.468085 (2150 2925);
PAINT GREEN (2150 2925);
DISPLAY INVISIBLE (2150 2925);
FORCEPROP 1 LAST NEEDS_NO_SIZE TRUE
J 0
(2300 2931);
DISPLAY 0.468085 (2300 2931);
PAINT GREEN (2300 2931);
DISPLAY INVISIBLE (2300 2931);
FORCEPROP 1 LAST PATH I64
J 0
(2150 2925);
DISPLAY 0.723404 (2150 2925);
PAINT GREEN (2150 2925);
DISPLAY INVISIBLE (2150 2925);
FORCEPROP 0 LAST $SEC 1
J 0
(1975 2825);
DISPLAY INVISIBLE (1975 2825);
FORCEPROP 0 LAST CDS_SEC 1
J 0
(1975 2825);
DISPLAY INVISIBLE (1975 2825);
FORCEADD MOSFET_NCH_1D3S..1
R 6
(2975 1450);
FORCEPROP 1 LAST PART_NUMBER BAMNR580000
J 0
(3127 1541);
DISPLAY 0.723404 (3127 1541);
PAINT WHITE (3127 1541);
DISPLAY INVISIBLE (3127 1541);
FORCEPROP 2 LAST PART_TYPE SMLF
J 0
(3150 1377);
DISPLAY 1.021277 (3150 1377);
FORCEPROP 1 LAST MATERIAL EMPTY
J 0
(3127 1600);
DISPLAY 0.723404 (3127 1600);
PAINT SKYBLUE (3127 1600);
FORCEPROP 2 LAST VALUE PSMNR58-30YLH
J 0
(3150 1427);
DISPLAY 0.723404 (3150 1427);
PAINT SKYBLUE (3150 1427);
FORCEPROP 2 LAST ROOM HSC1_BOM2
J 0
(3150 1650);
DISPLAY 1.021277 (3150 1650);
FORCEPROP 1 LAST LOCATION PPQ1
J 0
(3127 1484);
DISPLAY 0.723404 (3127 1484);
PAINT AQUA (3127 1484);
FORCEPROP 2 LASTPIN (3075 1200) $PN 1
R 1
J 2
(3065 1185);
DISPLAY 0.680851 (3065 1185);
PAINT MONO (3065 1185);
FORCEPROP 2 LASTPIN (2975 1200) $PN 2
R 1
J 2
(2965 1185);
DISPLAY 0.680851 (2965 1185);
PAINT MONO (2965 1185);
FORCEPROP 2 LASTPIN (2875 1200) $PN 3
R 1
J 2
(2865 1185);
DISPLAY 0.680851 (2865 1185);
PAINT MONO (2865 1185);
FORCEPROP 2 LASTPIN (2775 1400) $PN 4
J 2
(2765 1410);
DISPLAY 0.680851 (2765 1410);
PAINT MONO (2765 1410);
FORCEPROP 2 LASTPIN (2975 1700) $PN 5
R 1
J 0
(2965 1710);
DISPLAY 0.680851 (2965 1710);
PAINT MONO (2965 1710);
FORCEPROP 2 LAST SEC_TYPE 
J 0
(3150 1650);
DISPLAY 1.021277 (3150 1650);
DISPLAY INVISIBLE (3150 1650);
FORCEPROP 1 LAST NEEDS_NO_SIZE TRUE
J 0
(2975 1429);
DISPLAY 0.468085 (2975 1429);
PAINT GREEN (2975 1429);
DISPLAY INVISIBLE (2975 1429);
FORCEPROP 1 LAST CDS_LMAN_SYM_OUTLINE -150,200,150,-200
J 0
(2975 1450);
DISPLAY 0.468085 (2975 1450);
PAINT GREEN (2975 1450);
DISPLAY INVISIBLE (2975 1450);
FORCEPROP 2 LAST CDS_LIB pure_quanta
J 0
(2975 1450);
DISPLAY INVISIBLE (2975 1450);
FORCEPROP 1 LAST PATH I65
J 0
(2975 1450);
DISPLAY 0.723404 (2975 1450);
PAINT GREEN (2975 1450);
DISPLAY INVISIBLE (2975 1450);
FORCEPROP 2 LAST SEC 1
J 0
(3150 1650);
DISPLAY 0.680851 (3150 1650);
PAINT MONO (3150 1650);
DISPLAY INVISIBLE (3150 1650);
FORCEADD OFFPAGE..2
(3375 2300);
FORCEPROP 2 LAST $XR0 304 
J 0
(3564 2300);
DISPLAY 0.638298 (3564 2300);
PAINT MONO (3564 2300);
FORCEPROP 1 LAST OFFPAGE TRUE
J 0
(3700 2175);
DISPLAY 0.872340 (3700 2175);
PAINT AQUA (3700 2175);
DISPLAY INVISIBLE (3700 2175);
FORCEPROP 2 LAST CDS_LIB standard
J 0
(3375 2300);
DISPLAY INVISIBLE (3375 2300);
FORCEPROP 1 LAST COMMENT_BODY TRUE
J 0
(3330 2205);
DISPLAY 0.872340 (3330 2205);
PAINT GREEN (3330 2205);
DISPLAY INVISIBLE (3330 2205);
FORCEPROP 2 LAST PATH I66
J 0
(3575 2350);
DISPLAY 1.021277 (3575 2350);
DISPLAY INVISIBLE (3575 2350);
FORCEADD OFFPAGE..2
(3375 2900);
FORCEPROP 2 LAST $XR0 304 
J 0
(3564 2900);
DISPLAY 0.638298 (3564 2900);
PAINT MONO (3564 2900);
FORCEPROP 1 LAST OFFPAGE TRUE
J 0
(3700 2775);
DISPLAY 0.872340 (3700 2775);
PAINT AQUA (3700 2775);
DISPLAY INVISIBLE (3700 2775);
FORCEPROP 2 LAST CDS_LIB standard
J 0
(3375 2900);
DISPLAY INVISIBLE (3375 2900);
FORCEPROP 1 LAST COMMENT_BODY TRUE
J 0
(3330 2805);
DISPLAY 0.872340 (3330 2805);
PAINT GREEN (3330 2805);
DISPLAY INVISIBLE (3330 2805);
FORCEPROP 2 LAST PATH I67
J 0
(3575 2950);
DISPLAY 1.021277 (3575 2950);
DISPLAY INVISIBLE (3575 2950);
FORCEADD Q_CAP..1
(4025 675);
FORCEPROP 1 LAST PART_NUMBER CH3334K1B00
J 0
(4075 525);
DISPLAY 0.723404 (4075 525);
PAINT WHITE (4075 525);
DISPLAY INVISIBLE (4075 525);
FORCEPROP 1 LAST VALUE 33NF
J 0
(4075 725);
DISPLAY 0.723404 (4075 725);
PAINT SKYBLUE (4075 725);
FORCEPROP 1 LAST MATERIAL EMPTY
J 0
(4075 575);
DISPLAY 0.723404 (4075 575);
PAINT RED (4075 575);
FORCEPROP 1 LAST TOLERANCE 10%
J 0
(4075 625);
DISPLAY 0.723404 (4075 625);
PAINT SKYBLUE (4075 625);
FORCEPROP 1 LAST VOLTAGE 25V
J 0
(4075 675);
DISPLAY 0.723404 (4075 675);
PAINT SKYBLUE (4075 675);
FORCEPROP 1 LAST PACK_TYPE C0402
J 0
(4075 475);
DISPLAY 0.723404 (4075 475);
PAINT SKYBLUE (4075 475);
FORCEPROP 1 LAST LOCATION PC1750
J 0
(4075 775);
DISPLAY 0.978723 (4075 775);
FORCEPROP 1 LASTPIN (4025 775) $PN 1
J 0
(4035 755);
DISPLAY 0.787234 (4035 755);
PAINT MONO (4035 755);
FORCEPROP 1 LASTPIN (4025 575) $PN 2
J 0
(4035 555);
DISPLAY 0.787234 (4035 555);
PAINT MONO (4035 555);
FORCEPROP 2 LAST CDS_LIB pure_quanta
J 0
(4025 675);
DISPLAY INVISIBLE (4025 675);
FORCEPROP 1 LAST PATH I68
J 0
(4075 825);
DISPLAY 0.978723 (4075 825);
PAINT WHITE (4075 825);
DISPLAY INVISIBLE (4075 825);
FORCEPROP 0 LAST $SEC 1
J 0
(4075 825);
DISPLAY 0.680851 (4075 825);
PAINT MONO (4075 825);
DISPLAY INVISIBLE (4075 825);
FORCEPROP 0 LAST CDS_SEC 1
J 0
(4075 825);
DISPLAY 1.021277 (4075 825);
DISPLAY INVISIBLE (4075 825);
FORCEADD Q_CAP..1
(4500 375);
FORCEPROP 1 LAST PART_NUMBER CH21006KB16
J 0
(4550 325);
DISPLAY 0.574468 (4550 325);
PAINT WHITE (4550 325);
DISPLAY INVISIBLE (4550 325);
FORCEPROP 1 LAST MATERIAL EMPTY
J 0
(4550 350);
DISPLAY 0.574468 (4550 350);
PAINT RED (4550 350);
FORCEPROP 1 LAST VOLTAGE 50V
J 0
(4550 400);
DISPLAY 0.574468 (4550 400);
PAINT SKYBLUE (4550 400);
FORCEPROP 1 LAST VALUE 1NF
J 0
(4550 425);
DISPLAY 0.574468 (4550 425);
PAINT SKYBLUE (4550 425);
FORCEPROP 1 LAST TOLERANCE 10%
J 0
(4550 375);
DISPLAY 0.574468 (4550 375);
PAINT SKYBLUE (4550 375);
FORCEPROP 1 LAST PACK_TYPE 0402
J 0
(4550 300);
DISPLAY 0.574468 (4550 300);
PAINT SKYBLUE (4550 300);
FORCEPROP 1 LAST LOCATION PC1751
J 0
(4550 450);
DISPLAY 0.787234 (4550 450);
FORCEPROP 1 LASTPIN (4500 475) $PN 1
J 0
(4510 455);
DISPLAY 0.787234 (4510 455);
PAINT MONO (4510 455);
FORCEPROP 1 LASTPIN (4500 275) $PN 2
J 0
(4510 255);
DISPLAY 0.787234 (4510 255);
PAINT MONO (4510 255);
FORCEPROP 2 LAST CDS_LIB pure_quanta
J 0
(4500 375);
DISPLAY INVISIBLE (4500 375);
FORCEPROP 1 LAST PATH I69
J 0
(4550 525);
DISPLAY 0.978723 (4550 525);
PAINT WHITE (4550 525);
DISPLAY INVISIBLE (4550 525);
FORCEPROP 0 LAST $SEC 1
J 0
(4550 500);
DISPLAY 0.680851 (4550 500);
PAINT MONO (4550 500);
DISPLAY INVISIBLE (4550 500);
FORCEPROP 0 LAST CDS_SEC 1
J 0
(4550 500);
DISPLAY 1.021277 (4550 500);
DISPLAY INVISIBLE (4550 500);
FORCEADD Q_RES..2
(4500 700);
FORCEPROP 1 LAST PART_NUMBER CS01002FB07
J 0
(4550 650);
DISPLAY 0.574468 (4550 650);
PAINT WHITE (4550 650);
DISPLAY INVISIBLE (4550 650);
FORCEPROP 1 LAST WATTAGE 1/16W
J 0
(4550 700);
DISPLAY 0.574468 (4550 700);
PAINT SKYBLUE (4550 700);
FORCEPROP 1 LAST TOLERANCE 1%
J 0
(4550 725);
DISPLAY 0.574468 (4550 725);
PAINT SKYBLUE (4550 725);
FORCEPROP 1 LAST MATERIAL EMPTY
J 0
(4550 675);
DISPLAY 0.574468 (4550 675);
PAINT RED (4550 675);
FORCEPROP 1 LAST VALUE 10
J 0
(4550 750);
DISPLAY 0.574468 (4550 750);
PAINT SKYBLUE (4550 750);
FORCEPROP 1 LAST PACK_TYPE 0402LF
J 0
(4550 625);
DISPLAY 0.574468 (4550 625);
PAINT SKYBLUE (4550 625);
FORCEPROP 1 LAST LOCATION PR2537
J 0
(4550 775);
DISPLAY 0.787234 (4550 775);
FORCEPROP 1 LASTPIN (4500 800) $PN 1
J 0
(4505 762);
DISPLAY 0.787234 (4505 762);
PAINT MONO (4505 762);
FORCEPROP 1 LASTPIN (4500 600) $PN 2
J 0
(4505 610);
DISPLAY 0.787234 (4505 610);
PAINT MONO (4505 610);
FORCEPROP 2 LAST CDS_LIB pure_quanta
J 0
(4500 700);
DISPLAY INVISIBLE (4500 700);
FORCEPROP 1 LAST PATH I70
J 0
(4550 875);
DISPLAY 0.978723 (4550 875);
PAINT WHITE (4550 875);
DISPLAY INVISIBLE (4550 875);
FORCEPROP 0 LAST $SEC 1
J 0
(4550 825);
DISPLAY 0.680851 (4550 825);
PAINT MONO (4550 825);
DISPLAY INVISIBLE (4550 825);
FORCEPROP 0 LAST CDS_SEC 1
J 0
(4550 825);
DISPLAY 1.021277 (4550 825);
DISPLAY INVISIBLE (4550 825);
FORCEADD GND..1
(5200 -25);
FORCEPROP 3 LASTPIN (5200 25) SIG_NAME GND\g
J 0
(5210 35);
DISPLAY 0.659574 (5210 35);
PAINT MONO (5210 35);
DISPLAY INVISIBLE (5210 35);
FORCEPROP 1 LAST SIZE 1B
J 0
(5275 -75);
DISPLAY 0.872340 (5275 -75);
PAINT AQUA (5275 -75);
DISPLAY INVISIBLE (5275 -75);
FORCEPROP 1 LAST HDL_POWER GND
J 0
(5200 125);
DISPLAY 1.170213 (5200 125);
PAINT GREEN (5200 125);
DISPLAY INVISIBLE (5200 125);
FORCEPROP 2 LAST ROOM VR_DDR1_POWER_STAGE
J 0
(4975 50);
DISPLAY INVISIBLE (4975 50);
FORCEPROP 2 LAST CDS_LIB logical_power
J 0
(5200 -25);
DISPLAY INVISIBLE (5200 -25);
FORCEPROP 1 LAST PATH I71
J 0
(5275 -25);
DISPLAY 0.872340 (5275 -25);
PAINT AQUA (5275 -25);
DISPLAY INVISIBLE (5275 -25);
FORCEADD SS15P3SM386A..1
R 1
(5200 475);
FORCEPROP 1 LAST PART_NUMBER BC015P3SZ00
J 2
(5100 50);
DISPLAY 0.723404 (5100 50);
PAINT WHITE (5100 50);
DISPLAY INVISIBLE (5100 50);
FORCEPROP 2 LAST PART_TYPE SMLF
J 2
(5100 175);
DISPLAY 1.021277 (5100 175);
FORCEPROP 1 LAST MATERIAL IC
J 2
(5100 -25);
DISPLAY 0.723404 (5100 -25);
PAINT SKYBLUE (5100 -25);
FORCEPROP 2 LAST VALUE SS15P3S-M3/86A
J 2
(5100 125);
DISPLAY 0.808511 (5100 125);
PAINT SKYBLUE (5100 125);
FORCEPROP 1 LAST LOCATION PD17
J 2
(5100 225);
DISPLAY 0.723404 (5100 225);
PAINT AQUA (5100 225);
FORCEPROP 0 LASTPIN (5150 200) $PN 1
R 1
J 2
(5140 190);
DISPLAY 0.680851 (5140 190);
PAINT MONO (5140 190);
FORCEPROP 0 LASTPIN (5250 200) $PN 2
R 1
J 2
(5240 190);
DISPLAY 0.680851 (5240 190);
PAINT MONO (5240 190);
FORCEPROP 0 LASTPIN (5200 750) $PN K
R 1
J 0
(5190 760);
DISPLAY 0.680851 (5190 760);
PAINT MONO (5190 760);
FORCEPROP 1 LAST NEEDS_NO_SIZE TRUE
R 1
J 0
(5200 475);
DISPLAY 0.723404 (5200 475);
PAINT GREEN (5200 475);
DISPLAY INVISIBLE (5200 475);
FORCEPROP 1 LAST CDS_LMAN_SYM_OUTLINE -125,100,125,-100
R 1
J 0
(5200 475);
DISPLAY 0.468085 (5200 475);
PAINT GREEN (5200 475);
DISPLAY INVISIBLE (5200 475);
FORCEPROP 2 LAST CDS_LIB pure_quanta
J 0
(5200 475);
DISPLAY INVISIBLE (5200 475);
FORCEPROP 1 LAST PATH I72
R 1
J 0
(5200 475);
DISPLAY 0.723404 (5200 475);
PAINT GREEN (5200 475);
DISPLAY INVISIBLE (5200 475);
FORCEPROP 0 LAST $SEC 1
R 1
J 0
(5300 575);
DISPLAY 0.680851 (5300 575);
PAINT MONO (5300 575);
DISPLAY INVISIBLE (5300 575);
FORCEPROP 0 LAST CDS_SEC 1
R 1
J 0
(5300 575);
DISPLAY 1.021277 (5300 575);
DISPLAY INVISIBLE (5300 575);
FORCEADD MOSFET_NCH_1D3S..1
R 6
(3850 1475);
FORCEPROP 1 LAST PART_NUMBER BAMNR580000
J 0
(4002 1566);
DISPLAY 0.723404 (4002 1566);
PAINT WHITE (4002 1566);
DISPLAY INVISIBLE (4002 1566);
FORCEPROP 2 LAST VALUE PSMNR58-30YLH
J 0
(4025 1452);
DISPLAY 0.723404 (4025 1452);
PAINT SKYBLUE (4025 1452);
FORCEPROP 1 LAST MATERIAL EMPTY
J 0
(4002 1625);
DISPLAY 0.723404 (4002 1625);
PAINT SKYBLUE (4002 1625);
FORCEPROP 2 LAST PART_TYPE SMLF
J 0
(4025 1402);
DISPLAY 1.021277 (4025 1402);
FORCEPROP 2 LAST ROOM HSC1_BOM2
J 0
(4025 1675);
DISPLAY 1.021277 (4025 1675);
FORCEPROP 1 LAST LOCATION PPQ2
J 0
(4002 1509);
DISPLAY 0.723404 (4002 1509);
PAINT AQUA (4002 1509);
FORCEPROP 2 LASTPIN (3950 1225) $PN 1
R 1
J 2
(3940 1215);
DISPLAY 0.680851 (3940 1215);
PAINT MONO (3940 1215);
FORCEPROP 2 LASTPIN (3850 1225) $PN 2
R 1
J 2
(3840 1215);
DISPLAY 0.680851 (3840 1215);
PAINT MONO (3840 1215);
FORCEPROP 2 LASTPIN (3750 1225) $PN 3
R 1
J 2
(3740 1215);
DISPLAY 0.680851 (3740 1215);
PAINT MONO (3740 1215);
FORCEPROP 2 LASTPIN (3650 1425) $PN 4
J 2
(3640 1435);
DISPLAY 0.680851 (3640 1435);
PAINT MONO (3640 1435);
FORCEPROP 2 LASTPIN (3850 1725) $PN 5
R 1
J 0
(3840 1735);
DISPLAY 0.680851 (3840 1735);
PAINT MONO (3840 1735);
FORCEPROP 2 LAST SEC_TYPE 
J 0
(4025 1675);
DISPLAY 1.021277 (4025 1675);
DISPLAY INVISIBLE (4025 1675);
FORCEPROP 2 LAST CDS_LIB pure_quanta
J 0
(3850 1475);
DISPLAY INVISIBLE (3850 1475);
FORCEPROP 1 LAST CDS_LMAN_SYM_OUTLINE -150,200,150,-200
J 0
(3850 1475);
DISPLAY 0.468085 (3850 1475);
PAINT GREEN (3850 1475);
DISPLAY INVISIBLE (3850 1475);
FORCEPROP 1 LAST NEEDS_NO_SIZE TRUE
J 0
(3850 1454);
DISPLAY 0.468085 (3850 1454);
PAINT GREEN (3850 1454);
DISPLAY INVISIBLE (3850 1454);
FORCEPROP 1 LAST PATH I73
J 0
(3850 1475);
DISPLAY 0.723404 (3850 1475);
PAINT GREEN (3850 1475);
DISPLAY INVISIBLE (3850 1475);
FORCEPROP 2 LAST SEC 1
J 0
(4025 1675);
DISPLAY 0.680851 (4025 1675);
PAINT MONO (4025 1675);
DISPLAY INVISIBLE (4025 1675);
FORCEADD OFFPAGE..4
R 2
(4275 1900);
FORCEPROP 2 LAST $XR0 305 
J 0
(3993 1900);
DISPLAY 0.638298 (3993 1900);
PAINT MONO (3993 1900);
FORCEPROP 2 LAST CDS_LIB standard
J 0
(4275 1900);
DISPLAY INVISIBLE (4275 1900);
FORCEPROP 1 LAST COMMENT_BODY TRUE
J 2
(4300 1800);
DISPLAY 0.872340 (4300 1800);
PAINT GREEN (4300 1800);
DISPLAY INVISIBLE (4300 1800);
FORCEPROP 1 LAST OFFPAGE TRUE
J 2
(3950 1775);
DISPLAY 0.872340 (3950 1775);
PAINT GREEN (3950 1775);
DISPLAY INVISIBLE (3950 1775);
FORCEPROP 2 LAST PATH I74
J 0
(4000 1950);
DISPLAY 1.021277 (4000 1950);
DISPLAY INVISIBLE (4000 1950);
FORCEADD UNIVERSAL_POWER..1
(4825 1275);
FORCEPROP 3 LASTPIN (4825 1225) SIG_NAME P12V_AUX\g
J 0
(4835 1235);
DISPLAY 0.659574 (4835 1235);
PAINT MONO (4835 1235);
DISPLAY INVISIBLE (4835 1235);
FORCEPROP 1 LAST HDL_POWER P12V_AUX
J 1
(4825 1325);
DISPLAY 0.723404 (4825 1325);
PAINT GREEN (4825 1325);
FORCEPROP 2 LAST CDS_LIB logical_power
J 0
(4825 1275);
DISPLAY INVISIBLE (4825 1275);
FORCEPROP 2 LAST ROOM AUX_SW
J 0
(4825 1375);
DISPLAY 0.617021 (4825 1375);
DISPLAY INVISIBLE (4825 1375);
FORCEPROP 2 LAST BOM_COST MIO_VRD_SB
J 0
(4825 1375);
DISPLAY 0.617021 (4825 1375);
PAINT PURPLE (4825 1375);
DISPLAY INVISIBLE (4825 1375);
FORCEPROP 1 LAST PATH I75
J 0
(4875 1300);
DISPLAY 0.872340 (4875 1300);
PAINT AQUA (4875 1300);
DISPLAY INVISIBLE (4875 1300);
FORCEADD Q_RES..2
(4800 2125);
FORCEPROP 1 LAST PART_NUMBER CS01002FB07
J 0
(4840 2000);
DISPLAY 0.723404 (4840 2000);
PAINT WHITE (4840 2000);
DISPLAY INVISIBLE (4840 2000);
FORCEPROP 1 LAST VALUE 10
J 0
(4845 2200);
DISPLAY 0.723404 (4845 2200);
PAINT SKYBLUE (4845 2200);
FORCEPROP 1 LAST TOLERANCE 1%
J 0
(4845 2150);
DISPLAY 0.723404 (4845 2150);
PAINT SKYBLUE (4845 2150);
FORCEPROP 1 LAST PACK_TYPE 0402LF
J 0
(4840 1950);
DISPLAY 0.723404 (4840 1950);
PAINT SKYBLUE (4840 1950);
FORCEPROP 1 LAST MATERIAL EMPTY
J 0
(4840 2050);
DISPLAY 0.723404 (4840 2050);
PAINT SKYBLUE (4840 2050);
FORCEPROP 1 LAST WATTAGE 1/16W
J 0
(4840 2100);
DISPLAY 0.723404 (4840 2100);
PAINT SKYBLUE (4840 2100);
FORCEPROP 2 LAST ROOM HSC1_BOM2
J 0
(4850 2300);
DISPLAY 1.021277 (4850 2300);
FORCEPROP 1 LAST LOCATION PR2538
J 0
(4845 2250);
DISPLAY 0.978723 (4845 2250);
FORCEPROP 1 LASTPIN (4800 2225) $PN 1
J 0
(4805 2187);
DISPLAY 0.787234 (4805 2187);
PAINT MONO (4805 2187);
FORCEPROP 1 LASTPIN (4800 2025) $PN 2
J 0
(4805 2035);
DISPLAY 0.787234 (4805 2035);
PAINT MONO (4805 2035);
FORCEPROP 2 LAST CDS_LIB pure_quanta
J 0
(4800 2125);
DISPLAY INVISIBLE (4800 2125);
FORCEPROP 1 LAST PATH I76
J 0
(4850 2300);
DISPLAY 0.978723 (4850 2300);
PAINT WHITE (4850 2300);
DISPLAY INVISIBLE (4850 2300);
FORCEPROP 0 LAST $SEC 1
J 0
(4850 2300);
DISPLAY 0.680851 (4850 2300);
PAINT MONO (4850 2300);
DISPLAY INVISIBLE (4850 2300);
FORCEPROP 0 LAST CDS_SEC 1
J 0
(4850 2300);
DISPLAY 1.021277 (4850 2300);
DISPLAY INVISIBLE (4850 2300);
FORCEADD MOSFET_NCH_1D3S..1
R 6
(5300 2625);
FORCEPROP 1 LAST PART_NUMBER BAMNR580000
J 0
(4850 3066);
DISPLAY 0.723404 (4850 3066);
PAINT WHITE (4850 3066);
DISPLAY INVISIBLE (4850 3066);
FORCEPROP 2 LAST VALUE PSMNR58-30YLH
J 0
(4850 2977);
DISPLAY 0.723404 (4850 2977);
PAINT SKYBLUE (4850 2977);
FORCEPROP 1 LAST MATERIAL EMPTY
J 0
(4850 3125);
DISPLAY 0.723404 (4850 3125);
PAINT SKYBLUE (4850 3125);
FORCEPROP 2 LAST PART_TYPE SMLF
J 0
(4850 2927);
DISPLAY 1.021277 (4850 2927);
FORCEPROP 2 LAST ROOM HSC1_BOM2
J 0
(4850 3175);
DISPLAY 1.021277 (4850 3175);
FORCEPROP 1 LAST LOCATION PPQ9
J 0
(4850 3025);
DISPLAY 0.723404 (4850 3025);
PAINT GREEN (4850 3025);
FORCEPROP 0 LASTPIN (5400 2375) $PN 1
R 1
J 2
(5390 2365);
DISPLAY 0.680851 (5390 2365);
PAINT MONO (5390 2365);
FORCEPROP 0 LASTPIN (5300 2375) $PN 2
R 1
J 2
(5290 2365);
DISPLAY 0.680851 (5290 2365);
PAINT MONO (5290 2365);
FORCEPROP 0 LASTPIN (5200 2375) $PN 3
R 1
J 2
(5190 2365);
DISPLAY 0.680851 (5190 2365);
PAINT MONO (5190 2365);
FORCEPROP 0 LASTPIN (5100 2575) $PN 4
J 2
(5090 2585);
DISPLAY 0.680851 (5090 2585);
PAINT MONO (5090 2585);
FORCEPROP 0 LASTPIN (5300 2875) $PN 5
R 1
J 0
(5290 2885);
DISPLAY 0.680851 (5290 2885);
PAINT MONO (5290 2885);
FORCEPROP 1 LAST CDS_LMAN_SYM_OUTLINE -150,200,150,-200
J 0
(5300 2625);
DISPLAY 0.468085 (5300 2625);
PAINT GREEN (5300 2625);
DISPLAY INVISIBLE (5300 2625);
FORCEPROP 2 LAST CDS_LIB pure_quanta
J 0
(5300 2625);
DISPLAY INVISIBLE (5300 2625);
FORCEPROP 1 LAST NEEDS_NO_SIZE TRUE
J 0
(5300 2604);
DISPLAY 0.468085 (5300 2604);
PAINT GREEN (5300 2604);
DISPLAY INVISIBLE (5300 2604);
FORCEPROP 1 LAST PATH I77
J 0
(5300 2625);
DISPLAY 0.723404 (5300 2625);
PAINT GREEN (5300 2625);
DISPLAY INVISIBLE (5300 2625);
FORCEPROP 0 LAST $SEC 1
J 0
(4850 3175);
DISPLAY 0.680851 (4850 3175);
PAINT MONO (4850 3175);
DISPLAY INVISIBLE (4850 3175);
FORCEPROP 0 LAST CDS_SEC 1
J 0
(4850 3175);
DISPLAY 1.021277 (4850 3175);
DISPLAY INVISIBLE (4850 3175);
FORCEADD Q_SP_RES4P..1
(2150 3500);
FORCEPROP 1 LAST PART_NUMBER SP_CS0000FFT04
J 0
(2000 3112);
DISPLAY 0.723404 (2000 3112);
PAINT WHITE (2000 3112);
DISPLAY INVISIBLE (2000 3112);
FORCEPROP 2 LAST VALUE 0.0003
J 0
(2000 3225);
DISPLAY 0.723404 (2000 3225);
PAINT SKYBLUE (2000 3225);
FORCEPROP 2 LAST PART_TYPE SMLF
J 0
(2000 3375);
DISPLAY 1.021277 (2000 3375);
FORCEPROP 1 LAST MATERIAL EMPTY
J 0
(2000 3052);
DISPLAY 0.723404 (2000 3052);
PAINT SKYBLUE (2000 3052);
FORCEPROP 2 LAST TOLERANCE 1%
J 0
(2000 3275);
DISPLAY 0.723404 (2000 3275);
PAINT SKYBLUE (2000 3275);
FORCEPROP 2 LAST WATTAGE 4W
J 0
(2000 3325);
DISPLAY 0.723404 (2000 3325);
PAINT SKYBLUE (2000 3325);
FORCEPROP 2 LAST ROOM HSC1_BOM2
J 0
(2100 3300);
DISPLAY 1.021277 (2100 3300);
FORCEPROP 1 LAST LOCATION PR2532
J 0
(2000 3170);
DISPLAY 0.723404 (2000 3170);
PAINT AQUA (2000 3170);
FORCEPROP 0 LASTPIN (1950 3525) $PN 1A
J 2
(1940 3539);
DISPLAY 0.723404 (1940 3539);
FORCEPROP 0 LASTPIN (1950 3475) $PN 1B
J 2
(1940 3489);
DISPLAY 0.723404 (1940 3489);
FORCEPROP 0 LASTPIN (2350 3525) $PN 2A
J 0
(2360 3539);
DISPLAY 0.723404 (2360 3539);
FORCEPROP 0 LASTPIN (2350 3475) $PN 2B
J 0
(2360 3489);
DISPLAY 0.723404 (2360 3489);
FORCEPROP 2 LAST CDS_LIB pure_quanta
J 0
(2150 3500);
DISPLAY INVISIBLE (2150 3500);
FORCEPROP 1 LAST CDS_LMAN_SYM_OUTLINE -150,75,150,-75
J 0
(2150 3500);
DISPLAY 0.468085 (2150 3500);
PAINT GREEN (2150 3500);
DISPLAY INVISIBLE (2150 3500);
FORCEPROP 1 LAST NEEDS_NO_SIZE TRUE
J 0
(2300 3506);
DISPLAY 0.468085 (2300 3506);
PAINT GREEN (2300 3506);
DISPLAY INVISIBLE (2300 3506);
FORCEPROP 1 LAST PATH I78
J 0
(2150 3500);
DISPLAY 0.723404 (2150 3500);
PAINT GREEN (2150 3500);
DISPLAY INVISIBLE (2150 3500);
FORCEPROP 0 LAST $SEC 1
J 0
(2000 3950);
DISPLAY INVISIBLE (2000 3950);
FORCEPROP 0 LAST CDS_SEC 1
J 0
(2000 3950);
DISPLAY INVISIBLE (2000 3950);
FORCEADD Q_SP_RES4P..1
(2175 4050);
FORCEPROP 1 LAST PART_NUMBER SP_CS0000FFT04
J 0
(2025 3667);
DISPLAY 0.723404 (2025 3667);
PAINT WHITE (2025 3667);
DISPLAY INVISIBLE (2025 3667);
FORCEPROP 2 LAST PART_TYPE SMLF
J 0
(2025 3930);
DISPLAY 1.021277 (2025 3930);
FORCEPROP 1 LAST MATERIAL EMPTY
J 0
(2025 3607);
DISPLAY 0.723404 (2025 3607);
PAINT SKYBLUE (2025 3607);
FORCEPROP 2 LAST VALUE 0.0003
J 0
(2025 3780);
DISPLAY 0.723404 (2025 3780);
PAINT SKYBLUE (2025 3780);
FORCEPROP 2 LAST WATTAGE 4W
J 0
(2025 3880);
DISPLAY 0.723404 (2025 3880);
PAINT SKYBLUE (2025 3880);
FORCEPROP 2 LAST TOLERANCE 1%
J 0
(2025 3830);
DISPLAY 0.723404 (2025 3830);
PAINT SKYBLUE (2025 3830);
FORCEPROP 2 LAST ROOM HSC1_BOM2
J 0
(2125 3825);
DISPLAY 1.021277 (2125 3825);
FORCEPROP 1 LAST LOCATION PR4
J 0
(2025 3725);
DISPLAY 0.723404 (2025 3725);
PAINT AQUA (2025 3725);
FORCEPROP 2 LASTPIN (1975 4075) $PN 1A
J 2
(1965 4033);
DISPLAY 0.680851 (1965 4033);
PAINT MONO (1965 4033);
FORCEPROP 2 LASTPIN (1975 4025) $PN 1B
J 2
(1965 3983);
DISPLAY 0.680851 (1965 3983);
PAINT MONO (1965 3983);
FORCEPROP 2 LASTPIN (2375 4075) $PN 2A
J 0
(2385 4033);
DISPLAY 0.680851 (2385 4033);
PAINT MONO (2385 4033);
FORCEPROP 2 LASTPIN (2375 4025) $PN 2B
J 0
(2385 3983);
DISPLAY 0.680851 (2385 3983);
PAINT MONO (2385 3983);
FORCEPROP 1 LAST NEEDS_NO_SIZE TRUE
J 0
(2325 4056);
DISPLAY 0.468085 (2325 4056);
PAINT GREEN (2325 4056);
DISPLAY INVISIBLE (2325 4056);
FORCEPROP 1 LAST CDS_LMAN_SYM_OUTLINE -150,75,150,-75
J 0
(2175 4028);
DISPLAY 0.468085 (2175 4028);
PAINT GREEN (2175 4028);
DISPLAY INVISIBLE (2175 4028);
FORCEPROP 2 LAST CDS_LIB pure_quanta
J 0
(2175 4003);
DISPLAY INVISIBLE (2175 4003);
FORCEPROP 2 LAST SEC_TYPE 
J 0
(2025 3502);
DISPLAY 1.021277 (2025 3502);
DISPLAY INVISIBLE (2025 3502);
FORCEPROP 1 LAST PATH I79
J 0
(2175 4050);
DISPLAY 0.723404 (2175 4050);
PAINT GREEN (2175 4050);
DISPLAY INVISIBLE (2175 4050);
FORCEPROP 2 LAST SEC 1
J 0
(2025 3518);
DISPLAY 0.680851 (2025 3518);
PAINT MONO (2025 3518);
DISPLAY INVISIBLE (2025 3518);
FORCEADD OFFPAGE..2
(3375 3475);
FORCEPROP 2 LAST $XR0 304 
J 0
(3564 3475);
DISPLAY 0.638298 (3564 3475);
PAINT MONO (3564 3475);
FORCEPROP 2 LAST CDS_LIB standard
J 0
(3375 3475);
DISPLAY INVISIBLE (3375 3475);
FORCEPROP 1 LAST COMMENT_BODY TRUE
J 0
(3330 3380);
DISPLAY 0.872340 (3330 3380);
PAINT GREEN (3330 3380);
DISPLAY INVISIBLE (3330 3380);
FORCEPROP 1 LAST OFFPAGE TRUE
J 0
(3700 3350);
DISPLAY 0.872340 (3700 3350);
PAINT AQUA (3700 3350);
DISPLAY INVISIBLE (3700 3350);
FORCEPROP 2 LAST PATH I81
J 0
(3575 3525);
DISPLAY 1.021277 (3575 3525);
DISPLAY INVISIBLE (3575 3525);
FORCEADD OFFPAGE..2
(3400 4025);
FORCEPROP 2 LAST $XR0 304 
J 0
(3589 4025);
DISPLAY 0.638298 (3589 4025);
PAINT MONO (3589 4025);
FORCEPROP 1 LAST OFFPAGE TRUE
J 0
(3725 3900);
DISPLAY 0.872340 (3725 3900);
PAINT AQUA (3725 3900);
DISPLAY INVISIBLE (3725 3900);
FORCEPROP 2 LAST CDS_LIB standard
J 0
(3400 4025);
DISPLAY INVISIBLE (3400 4025);
FORCEPROP 1 LAST COMMENT_BODY TRUE
J 0
(3355 3930);
DISPLAY 0.872340 (3355 3930);
PAINT GREEN (3355 3930);
DISPLAY INVISIBLE (3355 3930);
FORCEPROP 2 LAST PATH I82
J 0
(3600 4075);
DISPLAY 1.021277 (3600 4075);
DISPLAY INVISIBLE (3600 4075);
FORCEADD OFFPAGE..2
(3425 4425);
FORCEPROP 2 LAST $XR1 305 
J 0
(3734 4425);
DISPLAY 0.638298 (3734 4425);
PAINT MONO (3734 4425);
FORCEPROP 2 LAST $XR0 304 
J 0
(3614 4425);
DISPLAY 0.638298 (3614 4425);
PAINT MONO (3614 4425);
FORCEPROP 1 LAST COMMENT_BODY TRUE
J 0
(3380 4330);
DISPLAY 0.872340 (3380 4330);
PAINT GREEN (3380 4330);
DISPLAY INVISIBLE (3380 4330);
FORCEPROP 2 LAST CDS_LIB standard
J 0
(3425 4425);
DISPLAY INVISIBLE (3425 4425);
FORCEPROP 1 LAST OFFPAGE TRUE
J 0
(3750 4300);
DISPLAY 0.872340 (3750 4300);
PAINT AQUA (3750 4300);
DISPLAY INVISIBLE (3750 4300);
FORCEPROP 2 LAST PATH I83
J 0
(3750 4475);
DISPLAY 1.021277 (3750 4475);
DISPLAY INVISIBLE (3750 4475);
FORCEADD UNIVERSAL_POWER..1
(3925 4150);
FORCEPROP 3 LASTPIN (3925 4100) SIG_NAME P12V_MAIN_R\g
J 0
(3935 4110);
DISPLAY 0.659574 (3935 4110);
PAINT MONO (3935 4110);
DISPLAY INVISIBLE (3935 4110);
FORCEPROP 1 LAST HDL_POWER P12V_MAIN_R
J 1
(3925 4200);
DISPLAY 0.723404 (3925 4200);
PAINT GREEN (3925 4200);
FORCEPROP 2 LAST BOM_COST MIO_VRD_SB
J 0
(3925 4250);
DISPLAY 0.617021 (3925 4250);
PAINT PURPLE (3925 4250);
DISPLAY INVISIBLE (3925 4250);
FORCEPROP 2 LAST ROOM AUX_SW
J 0
(3925 4250);
DISPLAY 0.617021 (3925 4250);
DISPLAY INVISIBLE (3925 4250);
FORCEPROP 2 LAST CDS_LIB logical_power
J 0
(3925 4150);
DISPLAY INVISIBLE (3925 4150);
FORCEPROP 1 LAST PATH I84
J 0
(3975 4175);
DISPLAY 0.872340 (3975 4175);
PAINT AQUA (3975 4175);
DISPLAY INVISIBLE (3975 4175);
FORCEADD UNIVERSAL_POWER..1
(4325 4400);
FORCEPROP 3 LASTPIN (4325 4350) SIG_NAME P12V_MAIN_R_0\g
J 0
(4335 4360);
DISPLAY 0.659574 (4335 4360);
PAINT MONO (4335 4360);
DISPLAY INVISIBLE (4335 4360);
FORCEPROP 1 LAST HDL_POWER P12V_MAIN_R_0
J 1
(4325 4450);
DISPLAY 0.723404 (4325 4450);
PAINT GREEN (4325 4450);
FORCEPROP 2 LAST CDS_LIB logical_power
J 0
(4325 4400);
DISPLAY INVISIBLE (4325 4400);
FORCEPROP 2 LAST BOM_COST MIO_VRD_SB
J 0
(4325 4500);
DISPLAY 0.617021 (4325 4500);
PAINT PURPLE (4325 4500);
DISPLAY INVISIBLE (4325 4500);
FORCEPROP 2 LAST ROOM AUX_SW
J 0
(4325 4500);
DISPLAY 0.617021 (4325 4500);
DISPLAY INVISIBLE (4325 4500);
FORCEPROP 1 LAST PATH I85
J 0
(4375 4425);
DISPLAY 0.872340 (4375 4425);
PAINT AQUA (4375 4425);
DISPLAY INVISIBLE (4375 4425);
FORCEADD Q_RES..1
(-2600 2325);
FORCEPROP 1 LAST PART_NUMBER CS-1002FB04
J 0
(-2575 2125);
DISPLAY 0.723404 (-2575 2125);
PAINT WHITE (-2575 2125);
DISPLAY INVISIBLE (-2575 2125);
FORCEPROP 1 LAST MATERIAL EMPTY
J 0
(-2500 2375);
DISPLAY 0.723404 (-2500 2375);
PAINT SKYBLUE (-2500 2375);
FORCEPROP 1 LAST TOLERANCE 1%
J 0
(-2575 2375);
DISPLAY 0.723404 (-2575 2375);
PAINT SKYBLUE (-2575 2375);
FORCEPROP 1 LAST VALUE 1
J 2
(-2625 2375);
DISPLAY 0.723404 (-2625 2375);
PAINT SKYBLUE (-2625 2375);
FORCEPROP 2 LAST ROOM HSC1_BOM2
J 0
(-2325 2375);
DISPLAY 1.021277 (-2325 2375);
FORCEPROP 1 LAST LOCATION PR2522
J 0
(-2875 2325);
DISPLAY 0.723404 (-2875 2325);
PAINT AQUA (-2875 2325);
FORCEPROP 1 LASTPIN (-2700 2325) $PN 1
J 0
(-2688 2337);
DISPLAY 0.787234 (-2688 2337);
PAINT MONO (-2688 2337);
FORCEPROP 1 LASTPIN (-2500 2325) $PN 2
J 0
(-2538 2337);
DISPLAY 0.787234 (-2538 2337);
PAINT MONO (-2538 2337);
FORCEPROP 1 LAST PATH I86
J 0
(-2650 2475);
DISPLAY 0.978723 (-2650 2475);
PAINT WHITE (-2650 2475);
DISPLAY INVISIBLE (-2650 2475);
FORCEPROP 2 LAST CDS_LIB pure_quanta
J 0
(-2600 2325);
DISPLAY INVISIBLE (-2600 2325);
FORCEPROP 1 LAST PACK_TYPE 0402LF
J 0
(-2675 2275);
DISPLAY 0.723404 (-2675 2275);
PAINT SKYBLUE (-2675 2275);
DISPLAY INVISIBLE (-2675 2275);
FORCEPROP 1 LAST WATTAGE 1/16W
J 2
(-2275 2275);
DISPLAY 0.723404 (-2275 2275);
PAINT SKYBLUE (-2275 2275);
DISPLAY INVISIBLE (-2275 2275);
FORCEPROP 0 LAST $SEC 1
J 0
(-2500 2425);
DISPLAY 0.680851 (-2500 2425);
PAINT MONO (-2500 2425);
DISPLAY INVISIBLE (-2500 2425);
FORCEPROP 0 LAST CDS_SEC 1
J 0
(-2500 2425);
DISPLAY 1.021277 (-2500 2425);
DISPLAY INVISIBLE (-2500 2425);
FORCEADD Q_RES..1
(-2600 2225);
FORCEPROP 1 LAST PART_NUMBER CS-1002FB04
J 0
(-2575 2025);
DISPLAY 0.723404 (-2575 2025);
PAINT WHITE (-2575 2025);
DISPLAY INVISIBLE (-2575 2025);
FORCEPROP 1 LAST VALUE 1
J 2
(-2625 2275);
DISPLAY 0.723404 (-2625 2275);
PAINT SKYBLUE (-2625 2275);
FORCEPROP 1 LAST MATERIAL EMPTY
J 0
(-2500 2275);
DISPLAY 0.723404 (-2500 2275);
PAINT SKYBLUE (-2500 2275);
FORCEPROP 1 LAST TOLERANCE 1%
J 0
(-2575 2275);
DISPLAY 0.723404 (-2575 2275);
PAINT SKYBLUE (-2575 2275);
FORCEPROP 2 LAST ROOM HSC1_BOM2
J 0
(-2325 2275);
DISPLAY 1.021277 (-2325 2275);
FORCEPROP 1 LAST LOCATION PR2523
J 0
(-2875 2225);
DISPLAY 0.723404 (-2875 2225);
PAINT AQUA (-2875 2225);
FORCEPROP 1 LASTPIN (-2700 2225) $PN 1
J 0
(-2688 2237);
DISPLAY 0.787234 (-2688 2237);
PAINT MONO (-2688 2237);
FORCEPROP 1 LASTPIN (-2500 2225) $PN 2
J 0
(-2538 2237);
DISPLAY 0.787234 (-2538 2237);
PAINT MONO (-2538 2237);
FORCEPROP 1 LAST PATH I87
J 0
(-2650 2375);
DISPLAY 0.978723 (-2650 2375);
PAINT WHITE (-2650 2375);
DISPLAY INVISIBLE (-2650 2375);
FORCEPROP 2 LAST CDS_LIB pure_quanta
J 0
(-2600 2225);
DISPLAY INVISIBLE (-2600 2225);
FORCEPROP 1 LAST PACK_TYPE 0402LF
J 0
(-2675 2175);
DISPLAY 0.723404 (-2675 2175);
PAINT SKYBLUE (-2675 2175);
DISPLAY INVISIBLE (-2675 2175);
FORCEPROP 1 LAST WATTAGE 1/16W
J 2
(-2275 2175);
DISPLAY 0.723404 (-2275 2175);
PAINT SKYBLUE (-2275 2175);
DISPLAY INVISIBLE (-2275 2175);
FORCEPROP 0 LAST $SEC 1
J 0
(-2500 2325);
DISPLAY 0.680851 (-2500 2325);
PAINT MONO (-2500 2325);
DISPLAY INVISIBLE (-2500 2325);
FORCEPROP 0 LAST CDS_SEC 1
J 0
(-2500 2325);
DISPLAY 1.021277 (-2500 2325);
DISPLAY INVISIBLE (-2500 2325);
FORCEADD Q_RES..1
(-2600 2425);
FORCEPROP 1 LAST PART_NUMBER CS-1002FB04
J 0
(-2575 2225);
DISPLAY 0.723404 (-2575 2225);
PAINT WHITE (-2575 2225);
DISPLAY INVISIBLE (-2575 2225);
FORCEPROP 1 LAST MATERIAL EMPTY
J 0
(-2500 2475);
DISPLAY 0.723404 (-2500 2475);
PAINT SKYBLUE (-2500 2475);
FORCEPROP 1 LAST TOLERANCE 1%
J 0
(-2575 2475);
DISPLAY 0.723404 (-2575 2475);
PAINT SKYBLUE (-2575 2475);
FORCEPROP 1 LAST VALUE 1
J 2
(-2625 2475);
DISPLAY 0.723404 (-2625 2475);
PAINT SKYBLUE (-2625 2475);
FORCEPROP 2 LAST ROOM HSC1_BOM2
J 0
(-2325 2475);
DISPLAY 1.021277 (-2325 2475);
FORCEPROP 1 LAST LOCATION PR2521
J 0
(-2875 2425);
DISPLAY 0.723404 (-2875 2425);
PAINT AQUA (-2875 2425);
FORCEPROP 1 LASTPIN (-2700 2425) $PN 1
J 0
(-2688 2437);
DISPLAY 0.723404 (-2688 2437);
PAINT MONO (-2688 2437);
FORCEPROP 1 LASTPIN (-2500 2425) $PN 2
J 0
(-2538 2437);
DISPLAY 0.723404 (-2538 2437);
PAINT MONO (-2538 2437);
FORCEPROP 1 LAST PATH I88
J 0
(-2650 2575);
DISPLAY 0.978723 (-2650 2575);
PAINT WHITE (-2650 2575);
DISPLAY INVISIBLE (-2650 2575);
FORCEPROP 2 LAST CDS_LIB pure_quanta
J 0
(-2600 2425);
DISPLAY INVISIBLE (-2600 2425);
FORCEPROP 1 LAST PACK_TYPE 0402LF
J 0
(-2675 2375);
DISPLAY 0.723404 (-2675 2375);
PAINT SKYBLUE (-2675 2375);
DISPLAY INVISIBLE (-2675 2375);
FORCEPROP 1 LAST WATTAGE 1/16W
J 2
(-2275 2375);
DISPLAY 0.723404 (-2275 2375);
PAINT SKYBLUE (-2275 2375);
DISPLAY INVISIBLE (-2275 2375);
FORCEPROP 0 LAST $SEC 1
J 0
(-2125 2475);
DISPLAY INVISIBLE (-2125 2475);
FORCEPROP 0 LAST CDS_SEC 1
J 0
(-2125 2475);
DISPLAY INVISIBLE (-2125 2475);
FORCEADD Q_RES..1
(-2600 2525);
FORCEPROP 1 LAST PART_NUMBER CS-1002FB04
J 0
(-2575 2325);
DISPLAY 0.723404 (-2575 2325);
PAINT WHITE (-2575 2325);
DISPLAY INVISIBLE (-2575 2325);
FORCEPROP 1 LAST MATERIAL EMPTY
J 0
(-2500 2575);
DISPLAY 0.723404 (-2500 2575);
PAINT SKYBLUE (-2500 2575);
FORCEPROP 1 LAST TOLERANCE 1%
J 0
(-2575 2575);
DISPLAY 0.723404 (-2575 2575);
PAINT SKYBLUE (-2575 2575);
FORCEPROP 1 LAST VALUE 1
J 2
(-2625 2575);
DISPLAY 0.723404 (-2625 2575);
PAINT SKYBLUE (-2625 2575);
FORCEPROP 2 LAST ROOM HSC1_BOM2
J 0
(-2325 2575);
DISPLAY 1.021277 (-2325 2575);
FORCEPROP 1 LAST LOCATION PR2520
J 0
(-2875 2525);
DISPLAY 0.723404 (-2875 2525);
PAINT AQUA (-2875 2525);
FORCEPROP 1 LASTPIN (-2700 2525) $PN 1
J 0
(-2688 2537);
DISPLAY 0.723404 (-2688 2537);
PAINT MONO (-2688 2537);
FORCEPROP 1 LASTPIN (-2500 2525) $PN 2
J 0
(-2538 2537);
DISPLAY 0.723404 (-2538 2537);
PAINT MONO (-2538 2537);
FORCEPROP 1 LAST PATH I89
J 0
(-2650 2675);
DISPLAY 0.978723 (-2650 2675);
PAINT WHITE (-2650 2675);
DISPLAY INVISIBLE (-2650 2675);
FORCEPROP 1 LAST WATTAGE 1/16W
J 2
(-2275 2475);
DISPLAY 0.723404 (-2275 2475);
PAINT SKYBLUE (-2275 2475);
DISPLAY INVISIBLE (-2275 2475);
FORCEPROP 1 LAST PACK_TYPE 0402LF
J 0
(-2675 2475);
DISPLAY 0.723404 (-2675 2475);
PAINT SKYBLUE (-2675 2475);
DISPLAY INVISIBLE (-2675 2475);
FORCEPROP 2 LAST CDS_LIB pure_quanta
J 0
(-2600 2525);
DISPLAY INVISIBLE (-2600 2525);
FORCEPROP 0 LAST $SEC 1
J 0
(-2125 2575);
DISPLAY INVISIBLE (-2125 2575);
FORCEPROP 0 LAST CDS_SEC 1
J 0
(-2125 2575);
DISPLAY INVISIBLE (-2125 2575);
FORCEADD Q_RES..1
(-2600 3100);
FORCEPROP 1 LAST PART_NUMBER CS01002FB07
J 0
(-2575 2900);
DISPLAY 0.723404 (-2575 2900);
PAINT WHITE (-2575 2900);
DISPLAY INVISIBLE (-2575 2900);
FORCEPROP 1 LAST MATERIAL EMPTY
J 0
(-2500 3150);
DISPLAY 0.723404 (-2500 3150);
PAINT SKYBLUE (-2500 3150);
FORCEPROP 1 LAST VALUE 10
J 2
(-2625 3150);
DISPLAY 0.723404 (-2625 3150);
PAINT SKYBLUE (-2625 3150);
FORCEPROP 1 LAST TOLERANCE 1%
J 0
(-2575 3150);
DISPLAY 0.723404 (-2575 3150);
PAINT SKYBLUE (-2575 3150);
FORCEPROP 2 LAST ROOM HSC1_BOM2
J 0
(-2300 3150);
DISPLAY 1.021277 (-2300 3150);
FORCEPROP 1 LAST LOCATION PR2517
J 0
(-2850 3100);
DISPLAY 0.723404 (-2850 3100);
PAINT AQUA (-2850 3100);
FORCEPROP 1 LASTPIN (-2700 3100) $PN 1
J 0
(-2688 3112);
DISPLAY 0.787234 (-2688 3112);
PAINT MONO (-2688 3112);
FORCEPROP 1 LASTPIN (-2500 3100) $PN 2
J 0
(-2538 3112);
DISPLAY 0.787234 (-2538 3112);
PAINT MONO (-2538 3112);
FORCEPROP 1 LAST PATH I90
J 0
(-2650 3250);
DISPLAY 0.978723 (-2650 3250);
PAINT WHITE (-2650 3250);
DISPLAY INVISIBLE (-2650 3250);
FORCEPROP 1 LAST WATTAGE 1/16W
J 2
(-2275 3050);
DISPLAY 0.723404 (-2275 3050);
PAINT SKYBLUE (-2275 3050);
DISPLAY INVISIBLE (-2275 3050);
FORCEPROP 1 LAST PACK_TYPE 0402LF
J 0
(-2675 3050);
DISPLAY 0.723404 (-2675 3050);
PAINT SKYBLUE (-2675 3050);
DISPLAY INVISIBLE (-2675 3050);
FORCEPROP 2 LAST CDS_LIB pure_quanta
J 0
(-2600 3100);
DISPLAY INVISIBLE (-2600 3100);
FORCEPROP 0 LAST $SEC 1
J 0
(-2500 3200);
DISPLAY 0.680851 (-2500 3200);
PAINT MONO (-2500 3200);
DISPLAY INVISIBLE (-2500 3200);
FORCEPROP 0 LAST CDS_SEC 1
J 0
(-2500 3200);
DISPLAY 1.021277 (-2500 3200);
DISPLAY INVISIBLE (-2500 3200);
FORCEADD Q_RES..1
(-2600 3000);
FORCEPROP 1 LAST PART_NUMBER CS01002FB07
J 0
(-2575 2800);
DISPLAY 0.723404 (-2575 2800);
PAINT WHITE (-2575 2800);
DISPLAY INVISIBLE (-2575 2800);
FORCEPROP 1 LAST MATERIAL EMPTY
J 0
(-2500 3050);
DISPLAY 0.723404 (-2500 3050);
PAINT SKYBLUE (-2500 3050);
FORCEPROP 1 LAST TOLERANCE 1%
J 0
(-2575 3050);
DISPLAY 0.723404 (-2575 3050);
PAINT SKYBLUE (-2575 3050);
FORCEPROP 1 LAST VALUE 10
J 2
(-2625 3050);
DISPLAY 0.723404 (-2625 3050);
PAINT SKYBLUE (-2625 3050);
FORCEPROP 2 LAST ROOM HSC1_BOM2
J 0
(-2300 3050);
DISPLAY 1.021277 (-2300 3050);
FORCEPROP 1 LAST LOCATION PR2518
J 0
(-2850 3000);
DISPLAY 0.723404 (-2850 3000);
PAINT AQUA (-2850 3000);
FORCEPROP 1 LASTPIN (-2700 3000) $PN 1
J 0
(-2688 3012);
DISPLAY 0.787234 (-2688 3012);
PAINT MONO (-2688 3012);
FORCEPROP 1 LASTPIN (-2500 3000) $PN 2
J 0
(-2538 3012);
DISPLAY 0.787234 (-2538 3012);
PAINT MONO (-2538 3012);
FORCEPROP 1 LAST PATH I91
J 0
(-2650 3150);
DISPLAY 0.978723 (-2650 3150);
PAINT WHITE (-2650 3150);
DISPLAY INVISIBLE (-2650 3150);
FORCEPROP 1 LAST PACK_TYPE 0402LF
J 0
(-2675 2950);
DISPLAY 0.723404 (-2675 2950);
PAINT SKYBLUE (-2675 2950);
DISPLAY INVISIBLE (-2675 2950);
FORCEPROP 1 LAST WATTAGE 1/16W
J 2
(-2275 2950);
DISPLAY 0.723404 (-2275 2950);
PAINT SKYBLUE (-2275 2950);
DISPLAY INVISIBLE (-2275 2950);
FORCEPROP 2 LAST CDS_LIB pure_quanta
J 0
(-2600 3000);
DISPLAY INVISIBLE (-2600 3000);
FORCEPROP 0 LAST $SEC 1
J 0
(-2500 3100);
DISPLAY 0.680851 (-2500 3100);
PAINT MONO (-2500 3100);
DISPLAY INVISIBLE (-2500 3100);
FORCEPROP 0 LAST CDS_SEC 1
J 0
(-2500 3100);
DISPLAY 1.021277 (-2500 3100);
DISPLAY INVISIBLE (-2500 3100);
FORCEADD Q_RES..1
(-2600 2900);
FORCEPROP 1 LAST PART_NUMBER CS11002FB07
J 0
(-2575 2700);
DISPLAY 0.723404 (-2575 2700);
PAINT WHITE (-2575 2700);
DISPLAY INVISIBLE (-2575 2700);
FORCEPROP 1 LAST TOLERANCE 1%
J 0
(-2575 2950);
DISPLAY 0.723404 (-2575 2950);
PAINT SKYBLUE (-2575 2950);
FORCEPROP 1 LAST MATERIAL EMPTY
J 0
(-2500 2950);
DISPLAY 0.723404 (-2500 2950);
PAINT SKYBLUE (-2500 2950);
FORCEPROP 1 LAST VALUE 100
J 2
(-2650 2950);
DISPLAY 0.723404 (-2650 2950);
PAINT SKYBLUE (-2650 2950);
FORCEPROP 2 LAST ROOM HSC1_BOM2
J 0
(-2300 2950);
DISPLAY 1.021277 (-2300 2950);
FORCEPROP 1 LAST LOCATION PR2519
J 0
(-2850 2900);
DISPLAY 0.638298 (-2850 2900);
FORCEPROP 1 LASTPIN (-2700 2900) $PN 1
J 0
(-2688 2912);
DISPLAY 0.787234 (-2688 2912);
PAINT MONO (-2688 2912);
FORCEPROP 1 LASTPIN (-2500 2900) $PN 2
J 0
(-2538 2912);
DISPLAY 0.787234 (-2538 2912);
PAINT MONO (-2538 2912);
FORCEPROP 1 LAST PATH I92
J 0
(-2650 3050);
DISPLAY 0.978723 (-2650 3050);
PAINT WHITE (-2650 3050);
DISPLAY INVISIBLE (-2650 3050);
FORCEPROP 1 LAST PACK_TYPE 0402LF
J 0
(-2675 2850);
DISPLAY 0.723404 (-2675 2850);
PAINT SKYBLUE (-2675 2850);
DISPLAY INVISIBLE (-2675 2850);
FORCEPROP 1 LAST WATTAGE 1/16W
J 2
(-2275 2850);
DISPLAY 0.723404 (-2275 2850);
PAINT SKYBLUE (-2275 2850);
DISPLAY INVISIBLE (-2275 2850);
FORCEPROP 2 LAST CDS_LIB pure_quanta
J 0
(-2600 2900);
DISPLAY INVISIBLE (-2600 2900);
FORCEPROP 0 LAST $SEC 1
J 0
(-2500 3000);
DISPLAY 0.680851 (-2500 3000);
PAINT MONO (-2500 3000);
DISPLAY INVISIBLE (-2500 3000);
FORCEPROP 0 LAST CDS_SEC 1
J 0
(-2500 3000);
DISPLAY 1.021277 (-2500 3000);
DISPLAY INVISIBLE (-2500 3000);
FORCEADD Q_RES..1
(-2600 3300);
FORCEPROP 1 LAST PART_NUMBER CS01002FB07
J 0
(-2575 3100);
DISPLAY 0.723404 (-2575 3100);
PAINT WHITE (-2575 3100);
DISPLAY INVISIBLE (-2575 3100);
FORCEPROP 1 LAST MATERIAL EMPTY
J 0
(-2500 3350);
DISPLAY 0.723404 (-2500 3350);
PAINT SKYBLUE (-2500 3350);
FORCEPROP 1 LAST TOLERANCE 1%
J 0
(-2575 3350);
DISPLAY 0.723404 (-2575 3350);
PAINT SKYBLUE (-2575 3350);
FORCEPROP 1 LAST VALUE 10
J 2
(-2625 3350);
DISPLAY 0.723404 (-2625 3350);
PAINT SKYBLUE (-2625 3350);
FORCEPROP 2 LAST ROOM HSC1_BOM2
J 0
(-2300 3350);
DISPLAY 1.021277 (-2300 3350);
FORCEPROP 1 LAST LOCATION PR2515
J 0
(-2850 3300);
DISPLAY 0.723404 (-2850 3300);
PAINT AQUA (-2850 3300);
FORCEPROP 1 LASTPIN (-2700 3300) $PN 1
J 0
(-2688 3312);
DISPLAY 0.723404 (-2688 3312);
PAINT MONO (-2688 3312);
FORCEPROP 1 LASTPIN (-2500 3300) $PN 2
J 0
(-2538 3312);
DISPLAY 0.723404 (-2538 3312);
PAINT MONO (-2538 3312);
FORCEPROP 1 LAST PATH I93
J 0
(-2650 3450);
DISPLAY 0.978723 (-2650 3450);
PAINT WHITE (-2650 3450);
DISPLAY INVISIBLE (-2650 3450);
FORCEPROP 2 LAST CDS_LIB pure_quanta
J 0
(-2600 3300);
DISPLAY INVISIBLE (-2600 3300);
FORCEPROP 1 LAST PACK_TYPE 0402LF
J 0
(-2675 3250);
DISPLAY 0.723404 (-2675 3250);
PAINT SKYBLUE (-2675 3250);
DISPLAY INVISIBLE (-2675 3250);
FORCEPROP 1 LAST WATTAGE 1/16W
J 2
(-2275 3250);
DISPLAY 0.723404 (-2275 3250);
PAINT SKYBLUE (-2275 3250);
DISPLAY INVISIBLE (-2275 3250);
FORCEPROP 0 LAST $SEC 1
J 0
(-2125 3350);
DISPLAY INVISIBLE (-2125 3350);
FORCEPROP 0 LAST CDS_SEC 1
J 0
(-2125 3350);
DISPLAY INVISIBLE (-2125 3350);
FORCEADD Q_RES..1
(-2600 3200);
FORCEPROP 1 LAST PART_NUMBER CS01002FB07
J 0
(-2575 3000);
DISPLAY 0.723404 (-2575 3000);
PAINT WHITE (-2575 3000);
DISPLAY INVISIBLE (-2575 3000);
FORCEPROP 1 LAST MATERIAL EMPTY
J 0
(-2500 3250);
DISPLAY 0.723404 (-2500 3250);
PAINT SKYBLUE (-2500 3250);
FORCEPROP 1 LAST VALUE 10
J 2
(-2625 3250);
DISPLAY 0.723404 (-2625 3250);
PAINT SKYBLUE (-2625 3250);
FORCEPROP 1 LAST TOLERANCE 1%
J 0
(-2575 3250);
DISPLAY 0.723404 (-2575 3250);
PAINT SKYBLUE (-2575 3250);
FORCEPROP 2 LAST ROOM HSC1_BOM2
J 0
(-2300 3250);
DISPLAY 1.021277 (-2300 3250);
FORCEPROP 1 LAST LOCATION PR2516
J 0
(-2850 3200);
DISPLAY 0.723404 (-2850 3200);
PAINT AQUA (-2850 3200);
FORCEPROP 1 LASTPIN (-2700 3200) $PN 1
J 0
(-2688 3212);
DISPLAY 0.723404 (-2688 3212);
PAINT MONO (-2688 3212);
FORCEPROP 1 LASTPIN (-2500 3200) $PN 2
J 0
(-2538 3212);
DISPLAY 0.723404 (-2538 3212);
PAINT MONO (-2538 3212);
FORCEPROP 1 LAST PATH I94
J 0
(-2650 3350);
DISPLAY 0.978723 (-2650 3350);
PAINT WHITE (-2650 3350);
DISPLAY INVISIBLE (-2650 3350);
FORCEPROP 2 LAST CDS_LIB pure_quanta
J 0
(-2600 3200);
DISPLAY INVISIBLE (-2600 3200);
FORCEPROP 1 LAST PACK_TYPE 0402LF
J 0
(-2675 3150);
DISPLAY 0.723404 (-2675 3150);
PAINT SKYBLUE (-2675 3150);
DISPLAY INVISIBLE (-2675 3150);
FORCEPROP 1 LAST WATTAGE 1/16W
J 2
(-2275 3150);
DISPLAY 0.723404 (-2275 3150);
PAINT SKYBLUE (-2275 3150);
DISPLAY INVISIBLE (-2275 3150);
FORCEPROP 0 LAST $SEC 1
J 0
(-2125 3250);
DISPLAY INVISIBLE (-2125 3250);
FORCEPROP 0 LAST CDS_SEC 1
J 0
(-2125 3250);
DISPLAY INVISIBLE (-2125 3250);
FORCEADD Q_RES..1
(-2625 3750);
FORCEPROP 1 LAST PART_NUMBER CS-1002FB04
J 0
(-2600 3550);
DISPLAY 0.723404 (-2600 3550);
PAINT WHITE (-2600 3550);
DISPLAY INVISIBLE (-2600 3550);
FORCEPROP 1 LAST MATERIAL EMPTY
J 0
(-2525 3800);
DISPLAY 0.723404 (-2525 3800);
PAINT SKYBLUE (-2525 3800);
FORCEPROP 1 LAST TOLERANCE 1%
J 0
(-2600 3800);
DISPLAY 0.723404 (-2600 3800);
PAINT SKYBLUE (-2600 3800);
FORCEPROP 1 LAST VALUE 1
J 2
(-2650 3800);
DISPLAY 0.723404 (-2650 3800);
PAINT SKYBLUE (-2650 3800);
FORCEPROP 2 LAST ROOM HSC1_BOM2
J 0
(-2350 3800);
DISPLAY 1.021277 (-2350 3800);
FORCEPROP 1 LAST LOCATION PR2513
J 0
(-2875 3750);
DISPLAY 0.723404 (-2875 3750);
PAINT AQUA (-2875 3750);
FORCEPROP 1 LASTPIN (-2725 3750) $PN 1
J 0
(-2713 3762);
DISPLAY 0.787234 (-2713 3762);
PAINT MONO (-2713 3762);
FORCEPROP 1 LASTPIN (-2525 3750) $PN 2
J 0
(-2563 3762);
DISPLAY 0.787234 (-2563 3762);
PAINT MONO (-2563 3762);
FORCEPROP 1 LAST PATH I95
J 0
(-2675 3900);
DISPLAY 0.978723 (-2675 3900);
PAINT WHITE (-2675 3900);
DISPLAY INVISIBLE (-2675 3900);
FORCEPROP 1 LAST PACK_TYPE 0402LF
J 0
(-2700 3700);
DISPLAY 0.723404 (-2700 3700);
PAINT SKYBLUE (-2700 3700);
DISPLAY INVISIBLE (-2700 3700);
FORCEPROP 1 LAST WATTAGE 1/16W
J 2
(-2300 3700);
DISPLAY 0.723404 (-2300 3700);
PAINT SKYBLUE (-2300 3700);
DISPLAY INVISIBLE (-2300 3700);
FORCEPROP 2 LAST CDS_LIB pure_quanta
J 0
(-2625 3750);
DISPLAY INVISIBLE (-2625 3750);
FORCEPROP 0 LAST $SEC 1
J 0
(-2525 3850);
DISPLAY 0.680851 (-2525 3850);
PAINT MONO (-2525 3850);
DISPLAY INVISIBLE (-2525 3850);
FORCEPROP 0 LAST CDS_SEC 1
J 0
(-2525 3850);
DISPLAY 1.021277 (-2525 3850);
DISPLAY INVISIBLE (-2525 3850);
FORCEADD Q_RES..1
(-2625 3850);
FORCEPROP 1 LAST PART_NUMBER CS-1002FB04
J 0
(-2600 3650);
DISPLAY 0.723404 (-2600 3650);
PAINT WHITE (-2600 3650);
DISPLAY INVISIBLE (-2600 3650);
FORCEPROP 1 LAST MATERIAL EMPTY
J 0
(-2525 3900);
DISPLAY 0.723404 (-2525 3900);
PAINT SKYBLUE (-2525 3900);
FORCEPROP 1 LAST TOLERANCE 1%
J 0
(-2600 3900);
DISPLAY 0.723404 (-2600 3900);
PAINT SKYBLUE (-2600 3900);
FORCEPROP 1 LAST VALUE 1
J 2
(-2650 3900);
DISPLAY 0.723404 (-2650 3900);
PAINT SKYBLUE (-2650 3900);
FORCEPROP 2 LAST ROOM HSC1_BOM2
J 0
(-2350 3900);
DISPLAY 1.021277 (-2350 3900);
FORCEPROP 1 LAST LOCATION PR2512
J 0
(-2875 3850);
DISPLAY 0.723404 (-2875 3850);
PAINT AQUA (-2875 3850);
FORCEPROP 1 LASTPIN (-2725 3850) $PN 1
J 0
(-2713 3862);
DISPLAY 0.787234 (-2713 3862);
PAINT MONO (-2713 3862);
FORCEPROP 1 LASTPIN (-2525 3850) $PN 2
J 0
(-2563 3862);
DISPLAY 0.787234 (-2563 3862);
PAINT MONO (-2563 3862);
FORCEPROP 1 LAST PATH I96
J 0
(-2675 4000);
DISPLAY 0.978723 (-2675 4000);
PAINT WHITE (-2675 4000);
DISPLAY INVISIBLE (-2675 4000);
FORCEPROP 1 LAST WATTAGE 1/16W
J 2
(-2300 3800);
DISPLAY 0.723404 (-2300 3800);
PAINT SKYBLUE (-2300 3800);
DISPLAY INVISIBLE (-2300 3800);
FORCEPROP 1 LAST PACK_TYPE 0402LF
J 0
(-2700 3800);
DISPLAY 0.723404 (-2700 3800);
PAINT SKYBLUE (-2700 3800);
DISPLAY INVISIBLE (-2700 3800);
FORCEPROP 2 LAST CDS_LIB pure_quanta
J 0
(-2625 3850);
DISPLAY INVISIBLE (-2625 3850);
FORCEPROP 0 LAST $SEC 1
J 0
(-2525 3950);
DISPLAY 0.680851 (-2525 3950);
PAINT MONO (-2525 3950);
DISPLAY INVISIBLE (-2525 3950);
FORCEPROP 0 LAST CDS_SEC 1
J 0
(-2525 3950);
DISPLAY 1.021277 (-2525 3950);
DISPLAY INVISIBLE (-2525 3950);
FORCEADD Q_RES..1
(-2625 3650);
FORCEPROP 1 LAST PART_NUMBER CS01002FB07
J 0
(-2600 3450);
DISPLAY 0.723404 (-2600 3450);
PAINT WHITE (-2600 3450);
DISPLAY INVISIBLE (-2600 3450);
FORCEPROP 1 LAST MATERIAL EMPTY
J 0
(-2525 3700);
DISPLAY 0.723404 (-2525 3700);
PAINT SKYBLUE (-2525 3700);
FORCEPROP 1 LAST VALUE 10
J 2
(-2650 3700);
DISPLAY 0.723404 (-2650 3700);
PAINT SKYBLUE (-2650 3700);
FORCEPROP 1 LAST TOLERANCE 1%
J 0
(-2600 3700);
DISPLAY 0.723404 (-2600 3700);
PAINT SKYBLUE (-2600 3700);
FORCEPROP 2 LAST ROOM HSC1_BOM2
J 0
(-2325 3700);
DISPLAY 1.021277 (-2325 3700);
FORCEPROP 1 LAST LOCATION PR2514
J 0
(-2875 3650);
DISPLAY 0.638298 (-2875 3650);
FORCEPROP 1 LASTPIN (-2725 3650) $PN 1
J 0
(-2713 3662);
DISPLAY 0.787234 (-2713 3662);
PAINT MONO (-2713 3662);
FORCEPROP 1 LASTPIN (-2525 3650) $PN 2
J 0
(-2563 3662);
DISPLAY 0.787234 (-2563 3662);
PAINT MONO (-2563 3662);
FORCEPROP 1 LAST PATH I97
J 0
(-2675 3800);
DISPLAY 0.978723 (-2675 3800);
PAINT WHITE (-2675 3800);
DISPLAY INVISIBLE (-2675 3800);
FORCEPROP 1 LAST WATTAGE 1/16W
J 2
(-2300 3600);
DISPLAY 0.723404 (-2300 3600);
PAINT SKYBLUE (-2300 3600);
DISPLAY INVISIBLE (-2300 3600);
FORCEPROP 1 LAST PACK_TYPE 0402LF
J 0
(-2700 3600);
DISPLAY 0.723404 (-2700 3600);
PAINT SKYBLUE (-2700 3600);
DISPLAY INVISIBLE (-2700 3600);
FORCEPROP 2 LAST CDS_LIB pure_quanta
J 0
(-2625 3650);
DISPLAY INVISIBLE (-2625 3650);
FORCEPROP 0 LAST $SEC 1
J 0
(-2525 3750);
DISPLAY 0.680851 (-2525 3750);
PAINT MONO (-2525 3750);
DISPLAY INVISIBLE (-2525 3750);
FORCEPROP 0 LAST CDS_SEC 1
J 0
(-2525 3750);
DISPLAY 1.021277 (-2525 3750);
DISPLAY INVISIBLE (-2525 3750);
FORCEADD Q_RES..1
(-2625 4050);
FORCEPROP 1 LAST PART_NUMBER CS-1002FB04
J 0
(-2600 3850);
DISPLAY 0.723404 (-2600 3850);
PAINT WHITE (-2600 3850);
DISPLAY INVISIBLE (-2600 3850);
FORCEPROP 1 LAST MATERIAL EMPTY
J 0
(-2525 4100);
DISPLAY 0.723404 (-2525 4100);
PAINT SKYBLUE (-2525 4100);
FORCEPROP 1 LAST TOLERANCE 1%
J 0
(-2600 4100);
DISPLAY 0.723404 (-2600 4100);
PAINT SKYBLUE (-2600 4100);
FORCEPROP 1 LAST VALUE 1
J 2
(-2650 4100);
DISPLAY 0.723404 (-2650 4100);
PAINT SKYBLUE (-2650 4100);
FORCEPROP 2 LAST ROOM HSC1_BOM2
J 0
(-2325 4100);
DISPLAY 1.021277 (-2325 4100);
FORCEPROP 1 LAST LOCATION PR2510
J 0
(-2875 4050);
DISPLAY 0.723404 (-2875 4050);
PAINT AQUA (-2875 4050);
FORCEPROP 1 LASTPIN (-2725 4050) $PN 1
J 0
(-2713 4062);
DISPLAY 0.723404 (-2713 4062);
PAINT MONO (-2713 4062);
FORCEPROP 1 LASTPIN (-2525 4050) $PN 2
J 0
(-2563 4062);
DISPLAY 0.723404 (-2563 4062);
PAINT MONO (-2563 4062);
FORCEPROP 1 LAST PATH I98
J 0
(-2675 4200);
DISPLAY 0.978723 (-2675 4200);
PAINT WHITE (-2675 4200);
DISPLAY INVISIBLE (-2675 4200);
FORCEPROP 1 LAST WATTAGE 1/16W
J 2
(-2300 4000);
DISPLAY 0.723404 (-2300 4000);
PAINT SKYBLUE (-2300 4000);
DISPLAY INVISIBLE (-2300 4000);
FORCEPROP 1 LAST PACK_TYPE 0402LF
J 0
(-2700 4000);
DISPLAY 0.723404 (-2700 4000);
PAINT SKYBLUE (-2700 4000);
DISPLAY INVISIBLE (-2700 4000);
FORCEPROP 2 LAST CDS_LIB pure_quanta
J 0
(-2625 4050);
DISPLAY INVISIBLE (-2625 4050);
FORCEPROP 0 LAST $SEC 1
J 0
(-2150 4100);
DISPLAY INVISIBLE (-2150 4100);
FORCEPROP 0 LAST CDS_SEC 1
J 0
(-2150 4100);
DISPLAY INVISIBLE (-2150 4100);
FORCEADD Q_RES..1
(-2625 3950);
FORCEPROP 1 LAST PART_NUMBER CS-1002FB04
J 0
(-2600 3750);
DISPLAY 0.723404 (-2600 3750);
PAINT WHITE (-2600 3750);
DISPLAY INVISIBLE (-2600 3750);
FORCEPROP 1 LAST MATERIAL EMPTY
J 0
(-2525 4000);
DISPLAY 0.723404 (-2525 4000);
PAINT SKYBLUE (-2525 4000);
FORCEPROP 1 LAST TOLERANCE 1%
J 0
(-2600 4000);
DISPLAY 0.723404 (-2600 4000);
PAINT SKYBLUE (-2600 4000);
FORCEPROP 1 LAST VALUE 1
J 2
(-2650 4000);
DISPLAY 0.723404 (-2650 4000);
PAINT SKYBLUE (-2650 4000);
FORCEPROP 2 LAST ROOM HSC1_BOM2
J 0
(-2350 4000);
DISPLAY 1.021277 (-2350 4000);
FORCEPROP 1 LAST LOCATION PR2511
J 0
(-2875 3950);
DISPLAY 0.723404 (-2875 3950);
PAINT AQUA (-2875 3950);
FORCEPROP 1 LASTPIN (-2725 3950) $PN 1
J 0
(-2713 3962);
DISPLAY 0.723404 (-2713 3962);
PAINT MONO (-2713 3962);
FORCEPROP 1 LASTPIN (-2525 3950) $PN 2
J 0
(-2563 3962);
DISPLAY 0.723404 (-2563 3962);
PAINT MONO (-2563 3962);
FORCEPROP 1 LAST PATH I99
J 0
(-2675 4100);
DISPLAY 0.978723 (-2675 4100);
PAINT WHITE (-2675 4100);
DISPLAY INVISIBLE (-2675 4100);
FORCEPROP 1 LAST WATTAGE 1/16W
J 2
(-2300 3900);
DISPLAY 0.723404 (-2300 3900);
PAINT SKYBLUE (-2300 3900);
DISPLAY INVISIBLE (-2300 3900);
FORCEPROP 1 LAST PACK_TYPE 0402LF
J 0
(-2700 3900);
DISPLAY 0.723404 (-2700 3900);
PAINT SKYBLUE (-2700 3900);
DISPLAY INVISIBLE (-2700 3900);
FORCEPROP 2 LAST CDS_LIB pure_quanta
J 0
(-2625 3950);
DISPLAY INVISIBLE (-2625 3950);
FORCEPROP 0 LAST $SEC 1
J 0
(-2150 4000);
DISPLAY INVISIBLE (-2150 4000);
FORCEPROP 0 LAST CDS_SEC 1
J 0
(-2150 4000);
DISPLAY INVISIBLE (-2150 4000);
FORCEADD QUANTA_TITLE_BLOCK_C..1
(6025 -1750);
FORCEPROP 0 LAST CDS_CON_LAST_MODIFIED Fri Aug 25 14:05:16 2023
J 0
(4140 -1735);
PAINT MONO (4140 -1735);
DISPLAY INVISIBLE (4140 -1735);
FORCEPROP 2 LAST CUSTOM_TXT_CDS <XR_PAGE_TITLE>
J 0
(-1865 3500);
DISPLAY 0.638298 (-1865 3500);
PAINT PINK (-1865 3500);
DISPLAY INVISIBLE (-1865 3500);
FORCEPROP 2 LAST CUSTOM_TXT_CDS <CON_LAST_MODIFIED>
J 0
(4140 -1735);
DISPLAY 0.978723 (4140 -1735);
FORCEPROP 2 LAST CUSTOM_TXT_CDS <Q_REV>
J 0
(5841 -1647);
DISPLAY 1.212766 (5841 -1647);
FORCEPROP 2 LAST CUSTOM_TXT_CDS <CON_PAGE_NUM> OF <CON_TOTAL_PAGES>
J 0
(5579 -1732);
DISPLAY 0.978723 (5579 -1732);
FORCEPROP 2 LAST CUSTOM_TXT_CDS <Q_PROJ>
J 0
(3643 -1648);
DISPLAY 1.212766 (3643 -1648);
FORCEPROP 2 LAST CUSTOM_TXT_CDS <Q_NUMBER>
J 0
(4622 -1647);
DISPLAY 1.212766 (4622 -1647);
FORCEPROP 1 LAST CUSTOM_TXT_CDS <NAME_2>
J 0
(2850 -1700);
FORCEPROP 1 LAST CUSTOM_TXT_CDS <NAME_1>
J 0
(2850 -1575);
FORCEPROP 1 LAST Q_TITLE HSC MODULE(1/4)
J 0
(-3275 -1675);
DISPLAY 2.446809 (-3275 -1675);
PAINT GREEN (-3275 -1675);
FORCEPROP 1 LAST Q_DEPT 
J 1
(2262 -1701);
DISPLAY 1.957447 (2262 -1701);
PAINT GREEN (2262 -1701);
FORCEPROP 2 LAST CDS_XR_PAGE_TITLE CR-304 : @S9S_MB_2U_LIB.S9S_MB_2U(SCH_1):PAGE304
J 0
(-1865 3500);
DISPLAY 0.638298 (-1865 3500);
PAINT PINK (-1865 3500);
DISPLAY INVISIBLE (-1865 3500);
FORCEPROP 1 LAST COMMENT_BODY TRUE
J 0
(6037 -1763);
DISPLAY 0.978723 (6037 -1763);
PAINT GREEN (6037 -1763);
DISPLAY INVISIBLE (6037 -1763);
FORCEPROP 2 LAST CDS_LIB pure_quanta
J 0
(6025 -1750);
PAINT MONO (6025 -1750);
DISPLAY INVISIBLE (6025 -1750);
FORCEPROP 1 LAST CDS_LMAN_SYM_OUTLINE -9475,6775,100,-125
J 0
(6025 -1750);
DISPLAY 0.468085 (6025 -1750);
PAINT GREEN (6025 -1750);
DISPLAY INVISIBLE (6025 -1750);
FORCEPROP 2 LAST PAGE_BORDER TRUE
J 0
(-1865 3500);
DISPLAY 0.638298 (-1865 3500);
PAINT PINK (-1865 3500);
DISPLAY INVISIBLE (-1865 3500);
FORCEADD DNS..1
(-2525 1650);
PAINT RED (-2525 1650);
FORCEPROP 1 LAST COMMENT_BODY TRUE
R 1
J 0
(-2450 1425);
DISPLAY 0.872340 (-2450 1425);
PAINT GREEN (-2450 1425);
DISPLAY INVISIBLE (-2450 1425);
FORCEPROP 2 LAST CDS_LIB mstr_misc
J 0
(-2525 1650);
DISPLAY INVISIBLE (-2525 1650);
FORCEADD DNS..1
(-2525 1825);
PAINT RED (-2525 1825);
FORCEPROP 1 LAST COMMENT_BODY TRUE
R 1
J 0
(-2450 1600);
DISPLAY 0.872340 (-2450 1600);
PAINT GREEN (-2450 1600);
DISPLAY INVISIBLE (-2450 1600);
FORCEPROP 2 LAST CDS_LIB mstr_misc
J 0
(-2525 1825);
DISPLAY INVISIBLE (-2525 1825);
FORCEADD DNS..1
(-2550 2300);
PAINT RED (-2550 2300);
FORCEPROP 1 LAST COMMENT_BODY TRUE
R 1
J 0
(-2475 2075);
DISPLAY 0.872340 (-2475 2075);
PAINT GREEN (-2475 2075);
DISPLAY INVISIBLE (-2475 2075);
FORCEPROP 2 LAST CDS_LIB mstr_misc
J 0
(-2550 2300);
DISPLAY INVISIBLE (-2550 2300);
FORCEADD DNS..1
(-2550 2475);
PAINT RED (-2550 2475);
FORCEPROP 1 LAST COMMENT_BODY TRUE
R 1
J 0
(-2475 2250);
DISPLAY 0.872340 (-2475 2250);
PAINT GREEN (-2475 2250);
DISPLAY INVISIBLE (-2475 2250);
FORCEPROP 2 LAST CDS_LIB mstr_misc
J 0
(-2550 2475);
DISPLAY INVISIBLE (-2550 2475);
FORCEADD DNS..1
(-2550 3000);
PAINT RED (-2550 3000);
FORCEPROP 1 LAST COMMENT_BODY TRUE
R 1
J 0
(-2475 2775);
DISPLAY 0.872340 (-2475 2775);
PAINT GREEN (-2475 2775);
DISPLAY INVISIBLE (-2475 2775);
FORCEPROP 2 LAST CDS_LIB mstr_misc
J 0
(-2550 3000);
DISPLAY INVISIBLE (-2550 3000);
FORCEADD DNS..1
(-2550 3250);
PAINT RED (-2550 3250);
FORCEPROP 1 LAST COMMENT_BODY TRUE
R 1
J 0
(-2475 3025);
DISPLAY 0.872340 (-2475 3025);
PAINT GREEN (-2475 3025);
DISPLAY INVISIBLE (-2475 3025);
FORCEPROP 2 LAST CDS_LIB mstr_misc
J 0
(-2550 3250);
DISPLAY INVISIBLE (-2550 3250);
FORCEADD DNS..1
(-2625 3775);
PAINT RED (-2625 3775);
FORCEPROP 1 LAST COMMENT_BODY TRUE
R 1
J 0
(-2550 3550);
DISPLAY 0.872340 (-2550 3550);
PAINT GREEN (-2550 3550);
DISPLAY INVISIBLE (-2550 3550);
FORCEPROP 2 LAST CDS_LIB mstr_misc
J 0
(-2625 3775);
DISPLAY INVISIBLE (-2625 3775);
FORCEADD DNS..1
(-2600 4000);
PAINT RED (-2600 4000);
FORCEPROP 1 LAST COMMENT_BODY TRUE
R 1
J 0
(-2525 3775);
DISPLAY 0.872340 (-2525 3775);
PAINT GREEN (-2525 3775);
DISPLAY INVISIBLE (-2525 3775);
FORCEPROP 2 LAST CDS_LIB mstr_misc
J 0
(-2600 4000);
DISPLAY INVISIBLE (-2600 4000);
FORCEADD DNS..1
(3425 650);
PAINT RED (3425 650);
FORCEPROP 1 LAST COMMENT_BODY TRUE
R 1
J 0
(3500 425);
DISPLAY 0.872340 (3500 425);
PAINT GREEN (3500 425);
DISPLAY INVISIBLE (3500 425);
FORCEPROP 2 LAST CDS_LIB mstr_misc
J 0
(3425 650);
DISPLAY INVISIBLE (3425 650);
FORCEADD DNS..1
(2550 650);
PAINT RED (2550 650);
FORCEPROP 1 LAST COMMENT_BODY TRUE
R 1
J 0
(2625 425);
DISPLAY 0.872340 (2625 425);
PAINT GREEN (2625 425);
DISPLAY INVISIBLE (2625 425);
FORCEPROP 2 LAST CDS_LIB mstr_misc
J 0
(2550 650);
DISPLAY INVISIBLE (2550 650);
FORCEADD DNS..1
(1725 625);
PAINT RED (1725 625);
FORCEPROP 1 LAST COMMENT_BODY TRUE
R 1
J 0
(1800 400);
DISPLAY 0.872340 (1800 400);
PAINT GREEN (1800 400);
DISPLAY INVISIBLE (1800 400);
FORCEPROP 2 LAST CDS_LIB mstr_misc
J 0
(1725 625);
DISPLAY INVISIBLE (1725 625);
FORCEADD DNS..1
(850 650);
PAINT RED (850 650);
FORCEPROP 1 LAST COMMENT_BODY TRUE
R 1
J 0
(925 425);
DISPLAY 0.872340 (925 425);
PAINT GREEN (925 425);
DISPLAY INVISIBLE (925 425);
FORCEPROP 2 LAST CDS_LIB mstr_misc
J 0
(850 650);
DISPLAY INVISIBLE (850 650);
FORCEADD DNS..1
(-850 650);
PAINT RED (-850 650);
FORCEPROP 1 LAST COMMENT_BODY TRUE
R 1
J 0
(-775 425);
DISPLAY 0.872340 (-775 425);
PAINT GREEN (-775 425);
DISPLAY INVISIBLE (-775 425);
FORCEPROP 2 LAST CDS_LIB mstr_misc
J 0
(-850 650);
DISPLAY INVISIBLE (-850 650);
FORCEADD DNS..1
(0 650);
PAINT RED (0 650);
FORCEPROP 1 LAST COMMENT_BODY TRUE
R 1
J 0
(75 425);
DISPLAY 0.872340 (75 425);
PAINT GREEN (75 425);
DISPLAY INVISIBLE (75 425);
FORCEPROP 2 LAST CDS_LIB mstr_misc
J 0
(0 650);
DISPLAY INVISIBLE (0 650);
FORCEADD DNS..1
(-550 1325);
PAINT RED (-550 1325);
FORCEPROP 1 LAST COMMENT_BODY TRUE
R 1
J 0
(-475 1100);
DISPLAY 0.872340 (-475 1100);
PAINT GREEN (-475 1100);
DISPLAY INVISIBLE (-475 1100);
FORCEPROP 2 LAST CDS_LIB mstr_misc
J 0
(-550 1325);
DISPLAY INVISIBLE (-550 1325);
FORCEADD DNS..1
(400 1350);
PAINT RED (400 1350);
FORCEPROP 1 LAST COMMENT_BODY TRUE
R 1
J 0
(475 1125);
DISPLAY 0.872340 (475 1125);
PAINT GREEN (475 1125);
DISPLAY INVISIBLE (475 1125);
FORCEPROP 2 LAST CDS_LIB mstr_misc
J 0
(400 1350);
DISPLAY INVISIBLE (400 1350);
FORCEADD DNS..1
(1225 1350);
PAINT RED (1225 1350);
FORCEPROP 1 LAST COMMENT_BODY TRUE
R 1
J 0
(1300 1125);
DISPLAY 0.872340 (1300 1125);
PAINT GREEN (1300 1125);
DISPLAY INVISIBLE (1300 1125);
FORCEPROP 2 LAST CDS_LIB mstr_misc
J 0
(1225 1350);
DISPLAY INVISIBLE (1225 1350);
FORCEADD DNS..1
(2100 1375);
PAINT RED (2100 1375);
FORCEPROP 1 LAST COMMENT_BODY TRUE
R 1
J 0
(2175 1150);
DISPLAY 0.872340 (2175 1150);
PAINT GREEN (2175 1150);
DISPLAY INVISIBLE (2175 1150);
FORCEPROP 2 LAST CDS_LIB mstr_misc
J 0
(2100 1375);
DISPLAY INVISIBLE (2100 1375);
FORCEADD DNS..1
(2975 1350);
PAINT RED (2975 1350);
FORCEPROP 1 LAST COMMENT_BODY TRUE
R 1
J 0
(3050 1125);
DISPLAY 0.872340 (3050 1125);
PAINT GREEN (3050 1125);
DISPLAY INVISIBLE (3050 1125);
FORCEPROP 2 LAST CDS_LIB mstr_misc
J 0
(2975 1350);
DISPLAY INVISIBLE (2975 1350);
FORCEADD DNS..1
(3850 1400);
PAINT RED (3850 1400);
FORCEPROP 1 LAST COMMENT_BODY TRUE
R 1
J 0
(3925 1175);
DISPLAY 0.872340 (3925 1175);
PAINT GREEN (3925 1175);
DISPLAY INVISIBLE (3925 1175);
FORCEPROP 2 LAST CDS_LIB mstr_misc
J 0
(3850 1400);
DISPLAY INVISIBLE (3850 1400);
FORCEADD DNS..1
(4800 2100);
PAINT RED (4800 2100);
FORCEPROP 1 LAST COMMENT_BODY TRUE
R 1
J 0
(4875 1875);
DISPLAY 0.872340 (4875 1875);
PAINT GREEN (4875 1875);
DISPLAY INVISIBLE (4875 1875);
FORCEPROP 2 LAST CDS_LIB mstr_misc
J 0
(4800 2100);
DISPLAY INVISIBLE (4800 2100);
FORCEADD DNS..1
(5325 2575);
PAINT RED (5325 2575);
FORCEPROP 1 LAST COMMENT_BODY TRUE
R 1
J 0
(5400 2350);
DISPLAY 0.872340 (5400 2350);
PAINT GREEN (5400 2350);
DISPLAY INVISIBLE (5400 2350);
FORCEPROP 2 LAST CDS_LIB mstr_misc
J 0
(5325 2575);
DISPLAY INVISIBLE (5325 2575);
FORCEADD DNS..1
(2175 2325);
PAINT RED (2175 2325);
FORCEPROP 1 LAST COMMENT_BODY TRUE
R 1
J 0
(2250 2100);
DISPLAY 0.872340 (2250 2100);
PAINT GREEN (2250 2100);
DISPLAY INVISIBLE (2250 2100);
FORCEPROP 2 LAST CDS_LIB mstr_misc
J 0
(2175 2325);
DISPLAY INVISIBLE (2175 2325);
FORCEADD DNS..1
(2175 2950);
PAINT RED (2175 2950);
FORCEPROP 1 LAST COMMENT_BODY TRUE
R 1
J 0
(2250 2725);
DISPLAY 0.872340 (2250 2725);
PAINT GREEN (2250 2725);
DISPLAY INVISIBLE (2250 2725);
FORCEPROP 2 LAST CDS_LIB mstr_misc
J 0
(2175 2950);
DISPLAY INVISIBLE (2175 2950);
FORCEADD DNS..1
(2175 3525);
PAINT RED (2175 3525);
FORCEPROP 1 LAST COMMENT_BODY TRUE
R 1
J 0
(2250 3300);
DISPLAY 0.872340 (2250 3300);
PAINT GREEN (2250 3300);
DISPLAY INVISIBLE (2250 3300);
FORCEPROP 2 LAST CDS_LIB mstr_misc
J 0
(2175 3525);
DISPLAY INVISIBLE (2175 3525);
FORCEADD DNS..2
(4050 675);
PAINT RED (4050 675);
FORCEPROP 2 LAST CDS_LIB mstr_misc
J 0
(4050 675);
DISPLAY INVISIBLE (4050 675);
FORCEPROP 1 LAST COMMENT_BODY TRUE
R 1
J 0
(4125 450);
DISPLAY 0.872340 (4125 450);
PAINT GREEN (4125 450);
DISPLAY INVISIBLE (4125 450);
FORCEADD DNS..2
(4525 375);
PAINT RED (4525 375);
FORCEPROP 2 LAST CDS_LIB mstr_misc
J 0
(4525 375);
DISPLAY INVISIBLE (4525 375);
FORCEPROP 1 LAST COMMENT_BODY TRUE
R 1
J 0
(4600 150);
DISPLAY 0.872340 (4600 150);
PAINT GREEN (4600 150);
DISPLAY INVISIBLE (4600 150);
FORCEADD DNS..2
(4525 675);
PAINT RED (4525 675);
FORCEPROP 2 LAST CDS_LIB mstr_misc
J 0
(4525 675);
DISPLAY INVISIBLE (4525 675);
FORCEPROP 1 LAST COMMENT_BODY TRUE
R 1
J 0
(4600 450);
DISPLAY 0.872340 (4600 450);
PAINT GREEN (4600 450);
DISPLAY INVISIBLE (4600 450);
FORCEADD DNS..1
(2225 4050);
PAINT RED (2225 4050);
FORCEPROP 1 LAST COMMENT_BODY TRUE
R 1
J 0
(2300 3825);
DISPLAY 0.872340 (2300 3825);
PAINT GREEN (2300 3825);
DISPLAY INVISIBLE (2300 3825);
FORCEPROP 2 LAST CDS_LIB mstr_misc
J 0
(2225 4050);
DISPLAY INVISIBLE (2225 4050);
FORCEADD DNS..1
(2175 4375);
PAINT RED (2175 4375);
FORCEPROP 2 LAST CDS_LIB mstr_misc
J 0
(2175 4375);
DISPLAY INVISIBLE (2175 4375);
FORCEPROP 1 LAST COMMENT_BODY TRUE
R 1
J 0
(2250 4150);
DISPLAY 0.872340 (2250 4150);
PAINT GREEN (2250 4150);
DISPLAY INVISIBLE (2250 4150);
WIRE 16 -1 (50 4325)(50 4350);
WIRE 16 -1 (1825 4325)(50 4325);
WIRE 16 -1 (50 4225)(50 4325);
WIRE 16 -1 (4825 1225)(4825 900);
WIRE 16 -1 (4325 4325)(4325 4350);
WIRE 16 -1 (5300 4325)(4325 4325);
WIRE 16 -1 (4325 4325)(2300 4325);
WIRE 16 -1 (3925 4075)(3925 4100);
WIRE 16 -1 (3925 1800)(3925 4075);
WIRE 16 -1 (2550 4075)(3925 4075);
WIRE 16 -1 (50 3600)(50 3575);
WIRE 16 -1 (-450 3600)(50 3600);
WIRE 16 -1 (50 3650)(50 3600);
WIRE 16 -1 (5200 25)(5200 75);
WIRE 16 -1 (-875 1325)(-725 1325);
WIRE 16 -1 (-875 775)(-875 1325);
FORCEPROP 2 LAST SIG_NAME P12V_HSC_GATE_G1
R 1
J 0
(-885 750);
DISPLAY 0.723404 (-885 750);
WIRE 16 -1 (5400 2275)(5400 2375);
WIRE 16 -1 (5200 2375)(5200 2275);
WIRE 16 -1 (5300 2375)(5300 2275);
WIRE 16 -1 (5400 2275)(5300 2275);
WIRE 16 -1 (5250 2275)(5300 2275);
WIRE 16 -1 (5200 2275)(5250 2275);
WIRE 16 -1 (5250 2275)(5250 900);
WIRE 16 -1 (5200 900)(5200 750);
WIRE 16 -1 (5250 900)(5200 900);
WIRE 16 -1 (4825 900)(5200 900);
WIRE 16 -1 (4500 800)(4500 900);
WIRE 16 -1 (4500 900)(4825 900);
WIRE 16 -1 (4025 900)(4025 775);
WIRE 16 -1 (4025 900)(4500 900);
WIRE 16 -1 (4025 900)(3950 900);
WIRE 16 -1 (3950 1225)(3950 900);
WIRE 16 -1 (3850 900)(3950 900);
WIRE 16 -1 (3850 1225)(3850 900);
WIRE 16 -1 (3850 900)(3750 900);
WIRE 16 -1 (3750 1225)(3750 900);
WIRE 16 -1 (3075 900)(3750 900);
WIRE 16 -1 (3075 1200)(3075 900);
WIRE 16 -1 (2975 1200)(2975 900);
WIRE 16 -1 (3075 900)(2975 900);
WIRE 16 -1 (2975 900)(2875 900);
WIRE 16 -1 (2875 1200)(2875 900);
WIRE 16 -1 (2200 900)(2875 900);
WIRE 16 -1 (2200 1175)(2200 900);
WIRE 16 -1 (2200 900)(2100 900);
WIRE 16 -1 (2100 1175)(2100 900);
WIRE 16 -1 (2000 1175)(2000 900);
WIRE 16 -1 (2100 900)(2000 900);
WIRE 16 -1 (1325 900)(2000 900);
WIRE 16 -1 (1325 1175)(1325 900);
WIRE 16 -1 (1325 900)(1225 900);
WIRE 16 -1 (1225 1175)(1225 900);
WIRE 16 -1 (1225 900)(1125 900);
WIRE 16 -1 (1125 1175)(1125 900);
WIRE 16 -1 (450 1150)(450 900);
WIRE 16 -1 (450 900)(1125 900);
WIRE 16 -1 (450 900)(350 900);
WIRE 16 -1 (350 1150)(350 900);
WIRE 16 -1 (350 900)(250 900);
WIRE 16 -1 (250 1150)(250 900);
WIRE 16 -1 (-425 1125)(-425 900);
WIRE 16 -1 (250 900)(-425 900);
WIRE 16 -1 (-425 900)(-525 900);
WIRE 16 -1 (-525 1125)(-525 900);
WIRE 16 -1 (-625 900)(-525 900);
WIRE 16 -1 (-625 1125)(-625 900);
WIRE 16 -1 (0 1350)(150 1350);
WIRE 16 -1 (0 775)(0 1350);
FORCEPROP 2 LAST SIG_NAME P12V_HSC_GATE_G2
R 1
J 0
(-10 750);
DISPLAY 0.723404 (-10 750);
WIRE 16 -1 (2550 1400)(2550 775);
FORCEPROP 2 LAST SIG_NAME P12V_HSC_GATE_G5
R 1
J 0
(2540 760);
DISPLAY 0.723404 (2540 760);
WIRE 16 -1 (2775 1400)(2550 1400);
WIRE 16 -1 (3425 1425)(3650 1425);
WIRE 16 -1 (3425 775)(3425 1425);
FORCEPROP 2 LAST SIG_NAME P12V_HSC_GATE_G6
R 1
J 0
(3415 760);
DISPLAY 0.723404 (3415 760);
WIRE 16 -1 (2350 2350)(2550 2350);
WIRE 16 -1 (2550 2350)(2550 2950);
WIRE 16 -1 (2350 2950)(2550 2950);
WIRE 16 -1 (2550 2950)(2550 3525);
WIRE 16 -1 (2350 3525)(2550 3525);
WIRE 16 -1 (2550 4075)(2550 3525);
WIRE 16 -1 (2550 4075)(2375 4075);
WIRE 16 -1 (3925 1800)(3850 1800);
WIRE 16 -1 (3850 1725)(3850 1800);
WIRE 16 -1 (3850 1800)(3750 1800);
WIRE 16 -1 (3750 1800)(3750 1801);
WIRE 16 -1 (2975 1800)(2975 1700);
WIRE 16 -1 (2900 1801)(3750 1801);
WIRE 16 -1 (2900 1801)(2900 1800);
WIRE 16 -1 (2975 1800)(2900 1800);
WIRE 16 -1 (2100 1675)(2100 1800);
WIRE 16 -1 (2100 1800)(2900 1800);
WIRE 16 -1 (1225 1675)(1225 1800);
WIRE 16 -1 (1225 1800)(2100 1800);
WIRE 16 -1 (350 1650)(350 1800);
WIRE 16 -1 (350 1800)(1225 1800);
WIRE 16 -1 (-525 1800)(350 1800);
WIRE 16 -1 (-525 1625)(-525 1800);
WIRE 16 -1 (2350 2900)(3325 2900);
FORCEPROP 2 LAST SIG_NAME P12V_HSC_SENSE2_R3_N
J 0
(2665 2910);
DISPLAY 0.723404 (2665 2910);
WIRE 16 -1 (1825 4325)(2050 4325);
WIRE 16 -1 (1825 4075)(1975 4075);
WIRE 16 -1 (1825 4325)(1825 4075);
WIRE 16 -1 (1825 3525)(1950 3525);
WIRE 16 -1 (1825 4075)(1825 3525);
WIRE 16 -1 (1825 2950)(1950 2950);
WIRE 16 -1 (1825 2950)(1825 3525);
WIRE 16 -1 (1825 2350)(1950 2350);
WIRE 16 -1 (1825 2350)(1825 2950);
WIRE 16 -1 (-2900 1575)(-2675 1575);
WIRE 16 -1 (-2900 1675)(-2900 1575);
WIRE 16 -1 (-2900 1675)(-2675 1675);
WIRE 16 -1 (-2900 1675)(-2900 1775);
WIRE 16 -1 (-2675 1775)(-2900 1775);
WIRE 16 -1 (-2900 1875)(-2900 1775);
WIRE 16 -1 (-2900 1875)(-2675 1875);
WIRE 16 -1 (-2900 1975)(-2900 1875);
WIRE 16 -1 (-2900 1975)(-1650 1975);
FORCEPROP 2 LAST SIG_NAME P12V_HSC_SENSE2_N
J 0
(-2335 1985);
DISPLAY 0.723404 (-2335 1985);
WIRE 16 -1 (1950 2300)(1125 2300);
FORCEPROP 2 LAST SIG_NAME P12V_HSC_SENSE2_R4_P
J 0
(1115 2310);
DISPLAY 0.723404 (1115 2310);
WIRE 16 -1 (4500 250)(4500 275);
WIRE 16 -1 (4025 250)(4500 250);
WIRE 16 -1 (4025 450)(4025 250);
WIRE 16 -1 (4025 450)(4025 575);
WIRE 16 -1 (3425 575)(3425 450);
WIRE 16 -1 (3425 450)(4025 450);
WIRE 16 -1 (2550 575)(2550 450);
WIRE 16 -1 (2550 450)(3425 450);
WIRE 16 -1 (1700 575)(1700 450);
WIRE 16 -1 (1700 450)(2550 450);
WIRE 16 -1 (850 575)(850 450);
WIRE 16 -1 (1700 450)(850 450);
WIRE 16 -1 (0 450)(850 450);
WIRE 16 -1 (0 575)(0 450);
WIRE 16 -1 (-175 275)(-1275 275);
FORCEPROP 2 LAST SIG_NAME P12V_HSC_GATE2
J 0
(-1242 292);
DISPLAY 0.723404 (-1242 292);
WIRE 16 -1 (-175 275)(-175 450);
WIRE 16 -1 (0 450)(-175 450);
WIRE 16 -1 (-875 450)(-875 575);
WIRE 16 -1 (-875 450)(-175 450);
WIRE 16 -1 (2350 2300)(3325 2300);
FORCEPROP 2 LAST SIG_NAME P12V_HSC_SENSE2_R4_N
J 0
(2665 2310);
DISPLAY 0.723404 (2665 2310);
WIRE 16 -1 (-2900 3650)(-2725 3650);
WIRE 16 -1 (-2900 3750)(-2900 3650);
WIRE 16 -1 (-2900 3750)(-2725 3750);
WIRE 16 -1 (-2900 3850)(-2900 3750);
WIRE 16 -1 (-2900 3850)(-2725 3850);
WIRE 16 -1 (-2900 3850)(-2900 3950);
WIRE 16 -1 (-2900 3950)(-2725 3950);
WIRE 16 -1 (-2900 4050)(-2900 3950);
WIRE 16 -1 (-2900 4050)(-2725 4050);
WIRE 16 -1 (-2900 4150)(-2900 4050);
WIRE 16 -1 (-2900 4150)(-1675 4150);
FORCEPROP 2 LAST SIG_NAME P12V_HSC_ADC_P
J 0
(-2385 4160);
DISPLAY 0.723404 (-2385 4160);
WIRE 16 2175 (-550 3925)(550 3925);
WIRE 16 2175 (550 4300)(550 3925);
WIRE 16 2175 (-550 4300)(-550 3925);
WIRE 16 2175 (-550 4300)(550 4300);
WIRE 16 -1 (-450 3975)(-675 3975);
FORCEPROP 2 LAST SIG_NAME P12V_PSU_FUSE
J 0
(-485 3985);
DISPLAY 0.638298 (-485 3985);
PAINT WHITE (-485 3985);
WIRE 16 -1 (-450 3900)(-450 3975);
WIRE 16 -1 (50 3975)(-450 3975);
WIRE 16 -1 (50 3900)(50 3975);
WIRE 16 -1 (50 4025)(50 3975);
WIRE 16 -1 (5300 2875)(5300 4325);
WIRE 16 -1 (3350 4025)(2375 4025);
FORCEPROP 2 LAST SIG_NAME P12V_HSC_SENSE2_R1_N
J 0
(2665 4035);
DISPLAY 0.723404 (2665 4035);
WIRE 16 -1 (2200 4425)(3375 4425);
FORCEPROP 2 LAST SIG_NAME P12V_HSC_SENSE1_N
J 0
(2665 4435);
DISPLAY 0.723404 (2665 4435);
WIRE 16 -1 (2350 3475)(3325 3475);
FORCEPROP 2 LAST SIG_NAME P12V_HSC_SENSE2_R2_N
J 0
(2665 3485);
DISPLAY 0.723404 (2665 3485);
WIRE 16 -1 (1125 4025)(1975 4025);
FORCEPROP 2 LAST SIG_NAME P12V_HSC_SENSE2_R1_P
J 0
(1115 4035);
DISPLAY 0.723404 (1115 4035);
WIRE 16 -1 (4800 1900)(4325 1900);
FORCEPROP 2 LAST SIG_NAME P12V_HSC_GATE1
J 0
(4315 1910);
DISPLAY 0.723404 (4315 1910);
WIRE 16 -1 (4800 1900)(4800 2025);
WIRE 16 -1 (850 1375)(1025 1375);
WIRE 16 -1 (850 775)(850 1375);
FORCEPROP 2 LAST SIG_NAME P12V_HSC_GATE_G3
R 1
J 0
(840 750);
DISPLAY 0.723404 (840 750);
WIRE 16 -1 (-1650 1575)(-2475 1575);
FORCEPROP 2 LAST SIG_NAME P12V_HSC_SENSE2_R4_N
J 0
(-2335 1585);
DISPLAY 0.723404 (-2335 1585);
WIRE 16 -1 (-1650 2225)(-2500 2225);
FORCEPROP 2 LAST SIG_NAME P12V_HSC_SENSE2_R4_P
J 0
(-2360 2235);
DISPLAY 0.723404 (-2360 2235);
WIRE 16 -1 (-1650 2425)(-2500 2425);
FORCEPROP 2 LAST SIG_NAME P12V_HSC_SENSE2_R2_P
J 0
(-2360 2435);
DISPLAY 0.723404 (-2360 2435);
WIRE 16 -1 (-1650 2525)(-2500 2525);
FORCEPROP 2 LAST SIG_NAME P12V_HSC_SENSE2_R1_P
J 0
(-2360 2535);
DISPLAY 0.723404 (-2360 2535);
WIRE 16 -1 (-2900 2225)(-2700 2225);
WIRE 16 -1 (-2900 2325)(-2900 2225);
WIRE 16 -1 (-2900 2325)(-2700 2325);
WIRE 16 -1 (-2900 2325)(-2900 2425);
WIRE 16 -1 (-2900 2425)(-2700 2425);
WIRE 16 -1 (-2900 2525)(-2900 2425);
WIRE 16 -1 (-2900 2525)(-2700 2525);
WIRE 16 -1 (-2900 2625)(-2900 2525);
WIRE 16 -1 (-2900 2625)(-1650 2625);
FORCEPROP 2 LAST SIG_NAME P12V_HSC_SENSE2_P
J 0
(-2385 2635);
DISPLAY 0.723404 (-2385 2635);
WIRE 16 -1 (-1675 2900)(-2500 2900);
FORCEPROP 2 LAST SIG_NAME P12V_HSC_SENSE1_N
J 0
(-2360 2910);
DISPLAY 0.723404 (-2360 2910);
WIRE 16 -1 (-1675 3100)(-2500 3100);
FORCEPROP 2 LAST SIG_NAME P12V_HSC_SENSE2_R3_N
J 0
(-2360 3110);
DISPLAY 0.723404 (-2360 3110);
WIRE 16 -1 (-1675 3200)(-2500 3200);
FORCEPROP 2 LAST SIG_NAME P12V_HSC_SENSE2_R2_N
J 0
(-2360 3210);
DISPLAY 0.723404 (-2360 3210);
WIRE 16 -1 (-1675 3300)(-2500 3300);
FORCEPROP 2 LAST SIG_NAME P12V_HSC_SENSE2_R1_N
J 0
(-2360 3310);
DISPLAY 0.723404 (-2360 3310);
WIRE 16 -1 (-2900 2900)(-2700 2900);
WIRE 16 -1 (-2900 3000)(-2900 2900);
WIRE 16 -1 (-2900 3000)(-2700 3000);
WIRE 16 -1 (-2900 3100)(-2900 3000);
WIRE 16 -1 (-2900 3100)(-2700 3100);
WIRE 16 -1 (-2900 3100)(-2900 3200);
WIRE 16 -1 (-2700 3200)(-2900 3200);
WIRE 16 -1 (-2900 3300)(-2900 3200);
WIRE 16 -1 (-2900 3300)(-2700 3300);
WIRE 16 -1 (-2900 3400)(-2900 3300);
WIRE 16 -1 (-2900 3400)(-1675 3400);
FORCEPROP 2 LAST SIG_NAME P12V_HSC_ADC_N
J 0
(-2360 3410);
DISPLAY 0.723404 (-2360 3410);
WIRE 16 -1 (-1675 3650)(-2525 3650);
FORCEPROP 2 LAST SIG_NAME P12V_HSC_SENSE1_P
J 0
(-2385 3660);
DISPLAY 0.723404 (-2385 3660);
WIRE 16 -1 (-1675 3750)(-2525 3750);
FORCEPROP 2 LAST SIG_NAME P12V_HSC_SENSE2_R4_P
J 0
(-2385 3760);
DISPLAY 0.723404 (-2385 3760);
WIRE 16 -1 (-1675 4050)(-2525 4050);
FORCEPROP 2 LAST SIG_NAME P12V_HSC_SENSE2_R1_P
J 0
(-2385 4060);
DISPLAY 0.723404 (-2385 4060);
WIRE 16 -1 (-1675 3850)(-2525 3850);
FORCEPROP 2 LAST SIG_NAME P12V_HSC_SENSE2_R3_P
J 0
(-2385 3860);
DISPLAY 0.723404 (-2385 3860);
WIRE 16 -1 (-1675 3950)(-2525 3950);
FORCEPROP 2 LAST SIG_NAME P12V_HSC_SENSE2_R2_P
J 0
(-2385 3960);
DISPLAY 0.723404 (-2385 3960);
WIRE 16 -1 (-450 3650)(-450 3600);
WIRE 16 -1 (1700 1375)(1900 1375);
WIRE 16 -1 (1700 775)(1700 1375);
FORCEPROP 2 LAST SIG_NAME P12V_HSC_GATE_G4
R 1
J 0
(1690 760);
DISPLAY 0.723404 (1690 760);
WIRE 16 -1 (4800 2575)(4800 2225);
WIRE 16 -1 (5100 2575)(4800 2575);
FORCEPROP 2 LAST SIG_NAME MB0_CM_GATE_G0
R 1
J 0
(4790 2210);
DISPLAY 0.723404 (4790 2210);
WIRE 16 -1 (1150 4425)(2150 4425);
FORCEPROP 2 LAST SIG_NAME P12V_HSC_SENSE1_P
J 0
(1140 4435);
DISPLAY 0.723404 (1140 4435);
WIRE 16 -1 (-1650 1675)(-2475 1675);
FORCEPROP 2 LAST SIG_NAME P12V_HSC_SENSE2_R3_N
J 0
(-2335 1685);
DISPLAY 0.723404 (-2335 1685);
WIRE 16 -1 (-1675 3000)(-2500 3000);
FORCEPROP 2 LAST SIG_NAME P12V_HSC_SENSE2_R4_N
J 0
(-2360 3010);
DISPLAY 0.723404 (-2360 3010);
WIRE 16 -1 (5250 75)(5250 200);
WIRE 16 -1 (5250 75)(5200 75);
WIRE 16 -1 (5200 75)(5150 75);
WIRE 16 -1 (5150 200)(5150 75);
WIRE 16 -1 (1125 3475)(1950 3475);
FORCEPROP 2 LAST SIG_NAME P12V_HSC_SENSE2_R2_P
J 0
(1115 3485);
DISPLAY 0.723404 (1115 3485);
WIRE 16 -1 (1950 2900)(1125 2900);
FORCEPROP 2 LAST SIG_NAME P12V_HSC_SENSE2_R3_P
J 0
(1115 2910);
DISPLAY 0.723404 (1115 2910);
WIRE 16 -1 (-1650 2325)(-2500 2325);
FORCEPROP 2 LAST SIG_NAME P12V_HSC_SENSE2_R3_P
J 0
(-2360 2335);
DISPLAY 0.723404 (-2360 2335);
WIRE 16 -1 (-1650 1875)(-2475 1875);
FORCEPROP 2 LAST SIG_NAME P12V_HSC_SENSE2_R1_N
J 0
(-2335 1885);
DISPLAY 0.723404 (-2335 1885);
WIRE 16 -1 (-1650 1775)(-2475 1775);
FORCEPROP 2 LAST SIG_NAME P12V_HSC_SENSE2_R2_N
J 0
(-2335 1785);
DISPLAY 0.723404 (-2335 1785);
WIRE 16 -1 (4500 600)(4500 475);
FORCEPROP 2 LAST SIG_NAME P12V_HSC_GATE_RC
J 0
(4515 535);
DISPLAY 0.723404 (4515 535);
DOT 1 (2550 4075);
DOT 1 (1825 4325);
DOT 1 (1825 2950);
DOT 1 (-175 450);
DOT 1 (-525 900);
DOT 1 (-425 900);
DOT 1 (0 450);
DOT 1 (250 900);
DOT 1 (350 900);
DOT 1 (850 450);
DOT 1 (450 900);
DOT 1 (1125 900);
DOT 1 (1225 900);
DOT 1 (1325 900);
DOT 1 (350 1800);
DOT 1 (1225 1800);
DOT 1 (-450 3975);
DOT 1 (50 3600);
DOT 1 (50 3975);
DOT 1 (50 4325);
DOT 1 (1700 450);
DOT 1 (2000 900);
DOT 1 (2200 900);
DOT 1 (2100 900);
DOT 1 (2550 450);
DOT 1 (2875 900);
DOT 1 (2975 900);
DOT 1 (3425 450);
DOT 1 (3075 900);
DOT 1 (2100 1800);
DOT 1 (2900 1800);
DOT 1 (3750 900);
DOT 1 (3850 900);
DOT 1 (3950 900);
DOT 1 (4025 450);
DOT 1 (4025 900);
DOT 1 (4500 900);
DOT 1 (5200 75);
DOT 1 (4825 900);
DOT 1 (5200 900);
DOT 1 (3850 1800);
DOT 1 (5250 2275);
DOT 1 (5300 2275);
DOT 1 (1825 3525);
DOT 1 (1825 4075);
DOT 1 (2550 3525);
DOT 1 (3925 4075);
DOT 1 (4325 4325);
DOT 1 (-2900 2325);
DOT 1 (-2900 2525);
DOT 1 (-2900 2425);
DOT 1 (-2900 3000);
DOT 1 (-2900 3100);
DOT 1 (-2900 3300);
DOT 1 (-2900 3200);
DOT 1 (-2900 3750);
DOT 1 (-2900 3950);
DOT 1 (-2900 4050);
DOT 1 (-2900 1875);
DOT 1 (-2900 1775);
DOT 1 (-2900 1675);
DOT 1 (-2900 3850);
DOT 1 (2550 2950);
FORCENOTE
20211208 ADD FS1 
(-650 3375) 0;
DISPLAY LEFT (-650 3375);
DISPLAY 1.595745 (-650 3375);
PAINT PINK (-650 3375);
FORCENOTE
RDS(ON)=0.76M OHM 
(2725 1825) 0;
DISPLAY LEFT (2725 1825);
DISPLAY 1.021277 (2725 1825);
FORCENOTE
AT 4.5V, ID=300A
(1754 1829) 0;
DISPLAY LEFT (1754 1829);
DISPLAY 1.021277 (1754 1829);
FORCENOTE
FPH=220A
(-2475 4534) 0;
DISPLAY LEFT (-2475 4534);
DISPLAY 1.595745 (-2475 4534);
FORCENOTE
20220308 MODIFY FOR GT
(-1675 4700) 0;
DISPLAY LEFT (-1675 4700);
DISPLAY 2.510638 (-1675 4700);
PAINT PINK (-1675 4700);
FORCENOTE
HOT SWAT CIRCUIT
(-3196 4713) 0;
DISPLAY LEFT (-3196 4713);
DISPLAY 2.000000 (-3196 4713);
FORCENOTE
LATCH OFF MODE
(-3175 4275) 0;
DISPLAY LEFT (-3175 4275);
DISPLAY 1.021277 (-3175 4275);
FORCENOTE
UV =10.091V
(-3175 4400) 0;
DISPLAY LEFT (-3175 4400);
DISPLAY 1.021277 (-3175 4400);
FORCENOTE
OCP=240A
(-3200 4609) 0;
DISPLAY LEFT (-3200 4609);
DISPLAY 1.595745 (-3200 4609);
FORCENOTE
OCW=220A
(-3200 4534) 0;
DISPLAY LEFT (-3200 4534);
DISPLAY 1.595745 (-3200 4534);
FORCENOTE
OV =14.333V
(-3175 4450) 0;
DISPLAY LEFT (-3175 4450);
DISPLAY 1.021277 (-3175 4450);
QUIT
